G04 ================== begin FILE IDENTIFICATION RECORD ==================*
G04 Layout Name:  9324_DA0F0TMBIJ0_F0T_Motherboard_J_v01_20230324_0910.brd*
G04 Film Name:    pmb*
G04 File Format:  Gerber RS274X*
G04 File Origin:  Cadence Allegro 17.2-S081*
G04 Origin Date:  Sat Mar 25 08:44:54 2023*
G04 *
G04 Layer:  DRAWING FORMAT/TITLE_BLOCK_A*
G04 Layer:  VIA CLASS/PASTEMASK_BOTTOM*
G04 Layer:  PACKAGE GEOMETRY/PASTEMASK_BOTTOM*
G04 Layer:  DRAWING FORMAT/TITLE_BLOCK*
G04 Layer:  PIN/PASTEMASK_BOTTOM*
G04 Layer:  MANUFACTURING/PHOTOPLOT_OUTLINE*
G04 Layer:  DRAWING FORMAT/TITLE_DATA_PMB*
G04 *
G04 Offset:    (0.00 0.00)*
G04 Mirror:    No*
G04 Mode:      Positive*
G04 Rotation:  0*
G04 FullContactRelief:  No*
G04 UndefLineWidth:     6.00*
G04 ================== end FILE IDENTIFICATION RECORD ====================*
%FSLAX25Y25*MOIN*%
%IR0*IPPOS*OFA0.00000B0.00000*MIA0B0*SFA1.00000B1.00000*%
%ADD16O,.111X.062*%
%ADD49R,.02X.005*%
%ADD50R,.005X.02*%
%AMMACRO73*
21,1,.028,.032,0.0,0.0,135.*%
%ADD73MACRO73*%
%ADD39R,.126X.06*%
%ADD27C,.02*%
%ADD32R,.111X.095*%
%ADD65R,.13X.095*%
%ADD62O,.137X.064*%
%ADD37R,.095X.111*%
%ADD26R,.007X.032*%
%ADD13R,.024X.007*%
%ADD34C,.06*%
%ADD46C,.061*%
%ADD30C,.062*%
%ADD10C,.026*%
%ADD40C,.018*%
%ADD28C,.028*%
%ADD23C,.064*%
%ADD11C,.039*%
%ADD63C,.0193*%
%ADD35R,.06X.06*%
%ADD47R,.061X.061*%
%ADD31R,.062X.062*%
%ADD67R,.064X.064*%
%AMMACRO70*
4,1,28,-.00492,.00566,
-.00659,.00733,
-.00269,.01122,
-.002174,.011659,
-.001588,.011998,
-.000951,.01223,
-.000284,.012348,
.000393,.012348,
.001061,.012231,
.001697,.012,
.002284,.011661,
.002803,.011226,
.00284,.01119,
.01119,.00284,
.011631,.002326,
.011978,.001744,
.012217,.00111,
.012343,.000444,
.012352,-.000233,
.012243,-.000902,
.012019,-.001541,
.011688,-.002132,
.011259,-.002656,
.01122,-.00269,
.00733,-.00659,
.00566,-.00492,
-.00172,-.0123,
-.0123,-.00172,
-.00492,.00566,
0.0*
%
%ADD70MACRO70*%
%AMMACRO25*
4,1,28,-.00748,.00052,
-.00984,.00052,
-.00984,.00603,
-.009782,.006705,
-.009607,.007359,
-.009321,.007974,
-.008933,.008529,
-.008455,.009009,
-.0079,.009398,
-.007286,.009685,
-.006632,.009861,
-.005957,.00992,
-.00591,.00992,
.00591,.00992,
.006585,.009869,
.007242,.009701,
.007859,.009421,
.008418,.009039,
.008903,.008565,
.009297,.008015,
.009591,.007404,
.009773,.006751,
.00984,.006077,
.00984,.00603,
.00984,.00052,
.00748,.00052,
.00748,-.00991,
-.00748,-.00991,
-.00748,.00052,
0.0*
%
%ADD25MACRO25*%
%AMMACRO15*
4,1,28,.00052,.00748,
.00052,.00984,
.00603,.00984,
.006705,.009782,
.007359,.009607,
.007974,.009321,
.008529,.008933,
.009009,.008455,
.009398,.0079,
.009685,.007286,
.009861,.006632,
.00992,.005957,
.00992,.00591,
.00992,-.00591,
.009869,-.006585,
.009701,-.007242,
.009421,-.007859,
.009039,-.008418,
.008565,-.008903,
.008015,-.009297,
.007404,-.009591,
.006751,-.009773,
.006077,-.00984,
.00603,-.00984,
.00052,-.00984,
.00052,-.00748,
-.00991,-.00748,
-.00991,.00748,
.00052,.00748,
0.0*
%
%ADD15MACRO15*%
%AMMACRO54*
4,1,8,.0034,.0082,
-.0034,.0082,
-.0082,.0034,
-.0082,-.00341,
-.00341,-.0082,
.0034,-.0082,
.0082,-.0034,
.0082,.0034,
.0034,.0082,
0.0*
%
%ADD54MACRO54*%
%AMMACRO53*
4,1,8,.0082,-.0034,
.0082,.0034,
.0034,.0082,
-.00341,.0082,
-.0082,.00341,
-.0082,-.0034,
-.0034,-.0082,
.0034,-.0082,
.0082,-.0034,
0.0*
%
%ADD53MACRO53*%
%AMMACRO69*
4,1,28,-.00565,.00493,
-.00732,.0066,
-.01121,.0027,
-.011649,.002185,
-.011989,.001599,
-.012222,.000962,
-.01234,.000295,
-.012342,-.000382,
-.012225,-.001049,
-.011994,-.001686,
-.011657,-.002273,
-.011222,-.002793,
-.01119,-.00283,
-.00283,-.01119,
-.002313,-.011629,
-.00173,-.011974,
-.001096,-.012212,
-.00043,-.012337,
.000247,-.012344,
.000915,-.012234,
.001554,-.012009,
.002145,-.011677,
.002668,-.011247,
.0027,-.01121,
.0066,-.00732,
.00493,-.00565,
.0123,.00173,
.00173,.0123,
-.00565,.00493,
0.0*
%
%ADD69MACRO69*%
%AMMACRO24*
4,1,28,-.00748,-.00051,
-.00984,-.00051,
-.00984,-.00602,
-.009782,-.006695,
-.009607,-.007349,
-.009321,-.007964,
-.008933,-.008519,
-.008455,-.008998,
-.0079,-.009388,
-.007287,-.009675,
-.006632,-.009851,
-.005958,-.00991,
-.00591,-.00991,
.00591,-.00991,
.006585,-.009859,
.007242,-.009691,
.007859,-.009411,
.008418,-.009029,
.008903,-.008555,
.009297,-.008005,
.00959,-.007394,
.009773,-.006742,
.00984,-.006068,
.00984,-.00602,
.00984,-.00051,
.00748,-.00051,
.00748,.00992,
-.00748,.00992,
-.00748,-.00051,
0.0*
%
%ADD24MACRO24*%
%AMMACRO14*
4,1,28,-.00051,.00748,
-.00051,.00984,
-.00602,.00984,
-.006695,.009782,
-.007349,.009607,
-.007964,.009321,
-.008519,.008933,
-.008998,.008455,
-.009388,.0079,
-.009675,.007287,
-.009851,.006632,
-.00991,.005958,
-.00991,.00591,
-.00991,-.00591,
-.009859,-.006585,
-.009691,-.007242,
-.009411,-.007859,
-.009029,-.008418,
-.008555,-.008903,
-.008005,-.009297,
-.007394,-.00959,
-.006742,-.009773,
-.006068,-.00984,
-.00602,-.00984,
-.00051,-.00984,
-.00051,-.00748,
.00992,-.00748,
.00992,.00748,
-.00051,.00748,
0.0*
%
%ADD14MACRO14*%
%AMMACRO78*
21,1,.012,.015,0.0,0.0,45.*%
%ADD78MACRO78*%
%AMMACRO74*
21,1,.04,.05,0.0,0.0,45.*%
%ADD74MACRO74*%
%ADD43R,.015X.012*%
%ADD22R,.05X.04*%
%ADD48R,.012X.015*%
%ADD36R,.04X.05*%
%ADD59R,.04X.015*%
%ADD41R,.017X.02*%
%ADD33R,.02X.018*%
%AMMACRO77*
21,1,.016,.0041,0.0,0.0,135.*%
%ADD77MACRO77*%
%ADD52R,.018X.02*%
%ADD60R,.044X.014*%
%ADD42R,.032X.028*%
%ADD64R,.128X.135*%
%ADD61R,.052X.018*%
%ADD44R,.028X.032*%
%ADD17R,.046X.024*%
%ADD66R,.054X.044*%
%ADD57R,.054X.026*%
%ADD45R,.044X.054*%
%ADD38C,.315*%
%ADD29R,.026X.054*%
%ADD18R,.046X.017*%
%ADD58R,.059X.014*%
%ADD68R,.066X.017*%
%ADD51R,.056X.056*%
%AMMACRO71*
4,1,28,.00492,-.00566,
.00659,-.00733,
.00269,-.01122,
.002174,-.011659,
.001588,-.011998,
.000951,-.01223,
.000284,-.012348,
-.000393,-.012348,
-.001061,-.012231,
-.001697,-.012,
-.002284,-.011661,
-.002803,-.011226,
-.00284,-.01119,
-.01119,-.00284,
-.011631,-.002326,
-.011978,-.001744,
-.012217,-.00111,
-.012343,-.000444,
-.012352,.000233,
-.012243,.000902,
-.012019,.001541,
-.011688,.002132,
-.011259,.002656,
-.01122,.00269,
-.00733,.00659,
-.00566,.00492,
.00172,.0123,
.0123,.00172,
.00492,-.00566,
0.0*
%
%ADD71MACRO71*%
%AMMACRO19*
4,1,28,.00748,-.00052,
.00984,-.00052,
.00984,-.00603,
.009782,-.006705,
.009607,-.007359,
.009321,-.007974,
.008933,-.008529,
.008455,-.009009,
.0079,-.009398,
.007286,-.009685,
.006632,-.009861,
.005957,-.00992,
.00591,-.00992,
-.00591,-.00992,
-.006585,-.009869,
-.007242,-.009701,
-.007859,-.009421,
-.008418,-.009039,
-.008903,-.008565,
-.009297,-.008015,
-.009591,-.007404,
-.009773,-.006751,
-.00984,-.006077,
-.00984,-.00603,
-.00984,-.00052,
-.00748,-.00052,
-.00748,.00991,
.00748,.00991,
.00748,-.00052,
0.0*
%
%ADD19MACRO19*%
%AMMACRO12*
4,1,28,-.00052,-.00748,
-.00052,-.00984,
-.00603,-.00984,
-.006705,-.009782,
-.007359,-.009607,
-.007974,-.009321,
-.008529,-.008933,
-.009009,-.008455,
-.009398,-.0079,
-.009685,-.007286,
-.009861,-.006632,
-.00992,-.005957,
-.00992,-.00591,
-.00992,.00591,
-.009869,.006585,
-.009701,.007242,
-.009421,.007859,
-.009039,.008418,
-.008565,.008903,
-.008015,.009297,
-.007404,.009591,
-.006751,.009773,
-.006077,.00984,
-.00603,.00984,
-.00052,.00984,
-.00052,.00748,
.00991,.00748,
.00991,-.00748,
-.00052,-.00748,
0.0*
%
%ADD12MACRO12*%
%AMMACRO76*
4,1,28,.00329,-.00674,
.00447,-.00878,
-.0003,-.01154,
-.000915,-.011824,
-.00157,-.012,
-.002244,-.01206,
-.002919,-.012001,
-.003574,-.011826,
-.004188,-.01154,
-.004743,-.011152,
-.005223,-.010674,
-.005612,-.010119,
-.00563,-.01008,
-.01155,.00016,
-.011841,.000772,
-.012023,.001425,
-.012089,.002099,
-.012036,.002774,
-.011868,.00343,
-.011588,.004047,
-.011205,.004606,
-.010731,.00509,
-.01018,.005484,
-.01014,.00551,
-.00537,.00826,
-.00419,.00622,
.00484,.01143,
.01232,-.00152,
.00329,-.00674,
0.0*
%
%ADD76MACRO76*%
%AMMACRO56*
4,1,8,-.0034,-.0082,
.0034,-.0082,
.0082,-.0034,
.0082,.00341,
.00341,.0082,
-.0034,.0082,
-.0082,.0034,
-.0082,-.0034,
-.0034,-.0082,
0.0*
%
%ADD56MACRO56*%
%AMMACRO55*
4,1,8,-.0082,.0034,
-.0082,-.0034,
-.0034,-.0082,
.00341,-.0082,
.0082,-.00341,
.0082,.0034,
.0034,.0082,
-.0034,.0082,
-.0082,.0034,
0.0*
%
%ADD55MACRO55*%
%AMMACRO72*
4,1,28,.00565,-.00493,
.00732,-.0066,
.01121,-.0027,
.011649,-.002185,
.011989,-.001599,
.012222,-.000962,
.01234,-.000295,
.012342,.000382,
.012225,.001049,
.011994,.001686,
.011657,.002273,
.011222,.002793,
.01119,.00283,
.00283,.01119,
.002313,.011629,
.00173,.011974,
.001096,.012212,
.00043,.012337,
-.000247,.012344,
-.000915,.012234,
-.001554,.012009,
-.002145,.011677,
-.002668,.011247,
-.0027,.01121,
-.0066,.00732,
-.00493,.00565,
-.0123,-.00173,
-.00173,-.0123,
.00565,-.00493,
0.0*
%
%ADD72MACRO72*%
%AMMACRO21*
4,1,28,.00051,-.00748,
.00051,-.00984,
.00602,-.00984,
.006695,-.009782,
.007349,-.009607,
.007964,-.009321,
.008519,-.008933,
.008998,-.008455,
.009388,-.0079,
.009675,-.007287,
.009851,-.006632,
.00991,-.005958,
.00991,-.00591,
.00991,.00591,
.009859,.006585,
.009691,.007242,
.009411,.007859,
.009029,.008418,
.008555,.008903,
.008005,.009297,
.007394,.00959,
.006742,.009773,
.006068,.00984,
.00602,.00984,
.00051,.00984,
.00051,.00748,
-.00992,.00748,
-.00992,-.00748,
.00051,-.00748,
0.0*
%
%ADD21MACRO21*%
%AMMACRO20*
4,1,28,.00748,.00051,
.00984,.00051,
.00984,.00602,
.009782,.006695,
.009607,.007349,
.009321,.007964,
.008933,.008519,
.008455,.008998,
.0079,.009388,
.007287,.009675,
.006632,.009851,
.005958,.00991,
.00591,.00991,
-.00591,.00991,
-.006585,.009859,
-.007242,.009691,
-.007859,.009411,
-.008418,.009029,
-.008903,.008555,
-.009297,.008005,
-.00959,.007394,
-.009773,.006742,
-.00984,.006068,
-.00984,.00602,
-.00984,.00051,
-.00748,.00051,
-.00748,-.00992,
.00748,-.00992,
.00748,.00051,
0.0*
%
%ADD20MACRO20*%
%AMMACRO75*
4,1,28,.00418,-.00622,
.00536,-.00827,
.01013,-.00551,
.010687,-.005125,
.011167,-.004646,
.011556,-.004092,
.011844,-.003479,
.01202,-.002825,
.01208,-.00215,
.012022,-.001475,
.011848,-.00082,
.011563,-.000206,
.01154,-.00016,
.00563,.01007,
.005247,.010629,
.004774,.011114,
.004224,.011509,
.003614,.011803,
.002962,.011987,
.002288,.012054,
.001612,.012004,
.000956,.011837,
.000338,.011558,
.00029,.01153,
-.00448,.00878,
-.0033,.00673,
-.01233,.00152,
-.00485,-.01144,
.00418,-.00622,
0.0*
%
%ADD75MACRO75*%
%ADD79C,.006*%
G75*
%LPD*%
G75*
G54D10*
X14092Y287115D03*
X16925Y203366D03*
X17061Y196368D03*
X24720Y216362D03*
Y232362D03*
Y224362D03*
Y240362D03*
X29962Y401000D03*
X27520Y434992D03*
X30200Y754822D03*
X24647Y1262074D03*
X26050Y1252272D03*
X33500Y200862D03*
X33670Y192862D03*
Y208362D03*
Y232362D03*
X42500Y224409D03*
X33670Y240362D03*
X40000Y298707D03*
Y293392D03*
X36255Y304972D03*
X39320Y392269D03*
X40940Y387302D03*
X44350Y400582D03*
X38620Y447202D03*
X38340Y440992D03*
X33350Y434992D03*
X39000Y731600D03*
X48697Y952481D03*
Y959331D03*
X39505Y987865D03*
X39927Y1249845D03*
X40217Y1258925D03*
X47190Y1252034D03*
X47567Y1246625D03*
X48269Y1672771D03*
X54920Y185039D03*
Y177165D03*
X62020Y295952D03*
X53825Y421746D03*
X57920Y443702D03*
X55564Y449734D03*
X57595Y603476D03*
X51878Y733922D03*
X61539Y756113D03*
X63487Y761105D03*
X60997Y768875D03*
X54620Y1258892D03*
X56777Y1252098D03*
Y1314165D03*
X54478Y1663669D03*
X54535Y1658447D03*
X53333Y1671862D03*
X65000Y1681900D03*
X58325Y1679275D03*
X65881Y305426D03*
X71500Y390812D03*
X71772Y421746D03*
X75490Y432519D03*
X72981Y466385D03*
X80300Y641862D03*
X80241Y659011D03*
X80123Y664031D03*
X80135Y667933D03*
X74559Y667814D03*
X76565Y717949D03*
X78397Y952481D03*
Y959331D03*
X70852Y1250055D03*
X69877Y1259125D03*
X76890Y1252034D03*
X65600Y1318588D03*
X65240Y1326068D03*
X74100Y1613300D03*
X86490Y200787D03*
Y208661D03*
X85960Y224409D03*
X85788Y240157D03*
X87620Y285321D03*
X87845Y278798D03*
Y295798D03*
X87820Y302821D03*
X87654Y376026D03*
X87520Y386502D03*
X85826Y420319D03*
X84410Y438519D03*
X94811Y510173D03*
X93069Y631917D03*
X90565Y636612D03*
X97560Y637624D03*
X91027Y643276D03*
X95725Y654540D03*
X95860Y659622D03*
X83165Y652564D03*
X91078Y649584D03*
X83208Y646436D03*
X83004Y705141D03*
X97295Y699786D03*
X90000Y766798D03*
X85747Y994357D03*
X92630Y1251615D03*
X84390Y1258982D03*
X82241Y1252037D03*
X87450Y1251692D03*
X81900Y1613300D03*
X85800D03*
X96420Y1693803D03*
X113490Y216596D03*
X113400Y232128D03*
X107200Y393562D03*
X107301Y388071D03*
X101317Y431727D03*
X110756Y465968D03*
X113597Y488434D03*
X107419Y487807D03*
X112480Y507792D03*
X110689Y498271D03*
X112590Y503248D03*
X99773Y515606D03*
X98490Y629496D03*
X102269Y634466D03*
X107045Y661917D03*
X99021Y663732D03*
X103397Y667272D03*
X101512Y702939D03*
X98134Y722501D03*
X107852Y767065D03*
X108097Y952481D03*
Y959331D03*
X98905Y987865D03*
X100287Y1249926D03*
X99577Y1259125D03*
X106590Y1252034D03*
X109320Y1246422D03*
X103902Y1584337D03*
X104318Y1589352D03*
X100620Y1596367D03*
X100020Y1615821D03*
X104400Y1632385D03*
X104318Y1637862D03*
X99600Y1668332D03*
X99645Y1663217D03*
X99980Y1698921D03*
X115850Y186362D03*
X122000Y207362D03*
X116920Y207462D03*
X114087Y285495D03*
X118920Y278875D03*
X114087Y302854D03*
X119220Y306236D03*
X125007Y384071D03*
Y396071D03*
X119457Y392071D03*
X114507Y404571D03*
X128145Y453722D03*
X125070Y486736D03*
X124124Y495883D03*
X118652Y528860D03*
X129762Y531942D03*
X117430Y636052D03*
X114021Y669409D03*
X116567Y763774D03*
X130147Y1249975D03*
X129277Y1259125D03*
X114020Y1259032D03*
X114604Y1251348D03*
X118927Y1308685D03*
X118727Y1316695D03*
X123220Y1324662D03*
X116798Y1589352D03*
X119500Y1622380D03*
X124795Y1681846D03*
X128195Y1674362D03*
X127195Y1696362D03*
Y1704362D03*
X117426Y1726622D03*
X125720Y1719262D03*
X132490Y420062D03*
X138042Y480238D03*
X132833D03*
X139370Y492560D03*
X136982Y497090D03*
X131737Y496295D03*
X131295Y487822D03*
X137672Y502106D03*
X135428Y510312D03*
X138878Y512550D03*
X138408Y507366D03*
X139153Y516453D03*
X132600Y537072D03*
X131740Y640103D03*
X130530Y658172D03*
X130570Y653162D03*
X131600Y646861D03*
X130325Y699824D03*
Y708624D03*
Y717424D03*
X145181Y950660D03*
X145485Y959265D03*
X145147Y994357D03*
X136010Y1249882D03*
X141641Y1252037D03*
X144359Y1246662D03*
X143680Y1262582D03*
X145087Y1343175D03*
X144263Y1412275D03*
X136518Y1602410D03*
X136522Y1598410D03*
X137420Y1708362D03*
X144520Y1717562D03*
X134557Y1722778D03*
X137852Y1726572D03*
X154220Y375682D03*
X160090Y391170D03*
Y397470D03*
X152826Y439397D03*
Y434362D03*
X156306Y449045D03*
X161267Y503143D03*
X151378Y526924D03*
X149400Y766798D03*
X160465Y985165D03*
X159780Y1241732D03*
X157610Y1246842D03*
X158977Y1259125D03*
X159587Y1403924D03*
X152026Y1614138D03*
X158335Y1614452D03*
X161310Y1708022D03*
X148145Y1701862D03*
X173275Y393497D03*
X164000Y415362D03*
X163926Y425383D03*
X164000Y420362D03*
X163926Y430883D03*
Y443319D03*
X178546Y453806D03*
X174881Y950660D03*
X175185Y959265D03*
X164976Y1226342D03*
X165990Y1252034D03*
X171341Y1252037D03*
X173770Y1260192D03*
X176560Y1251812D03*
X171262Y1443390D03*
X164920Y1712017D03*
X163060Y1717017D03*
X178226Y1726517D03*
X172962Y1721234D03*
X169777Y1726517D03*
X178142Y1720652D03*
X187371Y425383D03*
Y430883D03*
X194440Y433895D03*
Y439565D03*
X193110Y672272D03*
X179100Y766798D03*
X188493Y1251400D03*
X188307Y1260475D03*
X182000Y1251762D03*
X182587Y1343945D03*
X193293Y1722197D03*
X188794Y1725092D03*
X204699Y423242D03*
Y428742D03*
X205251Y577002D03*
X204610Y571097D03*
X205251Y611002D03*
X198336Y608271D03*
X199164Y616481D03*
X205251Y642969D03*
X200654Y646271D03*
X200018Y677492D03*
X199541Y684554D03*
X208787Y768035D03*
X204332Y950909D03*
X205627Y959575D03*
X197317Y989785D03*
X203040Y1262074D03*
X195690Y1252034D03*
X201041Y1252037D03*
X209390Y1250614D03*
X197460Y1404675D03*
X203120Y1624782D03*
X208115Y1624217D03*
X195590Y1714517D03*
X196010Y1709017D03*
X208295Y1703362D03*
X199050Y1726431D03*
X224210Y431501D03*
X224305Y422977D03*
X219995Y426267D03*
X224210Y436619D03*
X218140Y440735D03*
X218010Y432735D03*
X223664Y443125D03*
X220000Y448735D03*
X212891Y566632D03*
X218159Y776523D03*
X218197Y952481D03*
Y959331D03*
X225057Y989205D03*
X226910Y1227939D03*
X218590Y1251362D03*
X219660Y1260492D03*
X225390Y1252034D03*
X221637Y1316075D03*
X223387Y1336305D03*
X223647Y1343905D03*
X227007Y1372165D03*
Y1382165D03*
X224780Y1443402D03*
X223590Y1635840D03*
X220142Y1640209D03*
X214120Y1713462D03*
X235701Y21582D03*
X241310Y20322D03*
X238063Y26232D03*
X239820Y54362D03*
X239720Y71862D03*
X239010Y78542D03*
X242215Y151788D03*
X230359Y461683D03*
X236267Y763585D03*
X237667Y1027975D03*
X239657Y1035555D03*
X233970Y1245182D03*
X240240Y1252562D03*
X230084Y1251546D03*
X232820Y1259352D03*
X233158Y1441976D03*
X246510Y20362D03*
X246360Y26852D03*
X253910Y115722D03*
X249735Y152694D03*
X259933Y141122D03*
X245490Y159702D03*
X255810Y405582D03*
X252500Y415862D03*
X258066Y426735D03*
X259845Y461117D03*
X257750Y450842D03*
X259510Y757822D03*
X254160Y959342D03*
X254520Y953922D03*
X248575Y988405D03*
X247667Y1027975D03*
X255530Y1057940D03*
X248047Y1261902D03*
X247973Y1249200D03*
X246867Y1632667D03*
X254625Y1632354D03*
X263240Y38122D03*
X266990Y41832D03*
X275120Y28562D03*
X275900Y48872D03*
X263320Y87662D03*
X273620Y96662D03*
X263550Y120922D03*
X269191Y121092D03*
X275797Y120245D03*
X265910Y125492D03*
X260600Y151062D03*
X264578Y159203D03*
X263430Y422235D03*
X262963Y443735D03*
X272500Y447735D03*
X263040Y448752D03*
X272500Y452862D03*
X268331Y738029D03*
X271057Y762425D03*
X273737Y779755D03*
X263747Y885135D03*
X269117Y881535D03*
X276147Y916225D03*
X269977Y965105D03*
X266486Y1038775D03*
X262170Y1255061D03*
X263790Y1248688D03*
X269427Y1381893D03*
X287000Y20862D03*
X290799Y28362D03*
X289400Y54222D03*
X287000Y139862D03*
X276825Y140462D03*
X290685Y165447D03*
X289137Y735275D03*
X288901Y774093D03*
X291215Y782792D03*
X284223Y784922D03*
X289797Y791505D03*
X282417Y880465D03*
X279217Y902685D03*
X289404Y1017414D03*
X281759Y1010061D03*
X291497Y1023995D03*
X276582Y1040899D03*
X284103Y1037625D03*
X289406Y1049524D03*
X290654Y1037501D03*
X287875Y1044423D03*
X299500Y22862D03*
X295520Y26362D03*
X300248Y28362D03*
X302720Y38182D03*
X293161Y50522D03*
X298550Y51602D03*
X303715Y50857D03*
X305247Y71567D03*
X301600Y82457D03*
X302310Y75673D03*
X295357Y88903D03*
X307820Y95724D03*
X305025Y144202D03*
X299628Y149203D03*
Y158703D03*
X295685Y165447D03*
X300520Y552262D03*
X307987Y577658D03*
X293805Y565997D03*
X298000Y587890D03*
X308417Y585158D03*
X308447Y592255D03*
X306144Y602225D03*
X297024Y603533D03*
X296664Y616633D03*
X294679Y685046D03*
X299900Y700962D03*
X306579Y740759D03*
X298197Y786070D03*
X308557Y793945D03*
X307030Y807499D03*
X303730Y887208D03*
X296604Y1029634D03*
X294343Y1044589D03*
X310400Y50362D03*
X323040Y73122D03*
X322875Y84318D03*
X316364Y89212D03*
X310459Y75892D03*
X320430Y78002D03*
X324733Y148598D03*
X309756Y177449D03*
X320270Y200462D03*
X323314Y210645D03*
X322658Y229254D03*
X319718Y223750D03*
X316444Y559125D03*
X317860Y572322D03*
X319520Y577658D03*
X312007Y588675D03*
X319520Y582658D03*
X316127Y592785D03*
X318560Y587632D03*
X311820Y598762D03*
X317386Y623207D03*
X310847Y716105D03*
X317967Y771875D03*
X311417Y782375D03*
X323576Y804265D03*
X315274Y803537D03*
X310049Y813653D03*
X316354Y812166D03*
X310694Y897810D03*
X313886Y904524D03*
X310482Y909310D03*
X325182Y978814D03*
X317202Y970250D03*
X310839Y1023569D03*
X316808Y1033357D03*
X321078Y1038165D03*
X324515Y1060974D03*
X319515D03*
X321739Y1056828D03*
X311117Y1323175D03*
X323247Y1320875D03*
X311117Y1333175D03*
X310608Y1361189D03*
X335575Y214170D03*
X328588Y209677D03*
X328939Y229139D03*
X335385Y235309D03*
X335412Y222176D03*
X341295Y290239D03*
X336270Y402992D03*
X329050Y607402D03*
X331839Y789287D03*
X335473Y782485D03*
X326097Y796665D03*
X341584Y832077D03*
X333877Y869405D03*
X330963Y887959D03*
X326277Y919725D03*
X329807Y968595D03*
Y958595D03*
X327617Y1017035D03*
X341027Y1048921D03*
X325637Y1040899D03*
X327108Y1056694D03*
X336727Y1063055D03*
X330667Y1064105D03*
X331693Y1087864D03*
X325693D03*
X343040Y122522D03*
X343450Y131167D03*
X355189Y144267D03*
X351100Y150412D03*
X356295Y219362D03*
X353145Y228362D03*
X354145Y290591D03*
X343354Y391643D03*
X351422Y700972D03*
X348730Y735098D03*
X344377Y785725D03*
X349637Y986855D03*
X342231Y1055058D03*
X342289Y1338168D03*
X366775Y127662D03*
X366675Y158702D03*
X364014Y366391D03*
X371370Y373622D03*
X364014Y378649D03*
X370200Y409582D03*
X373720Y431362D03*
X365720Y440562D03*
X359639Y690114D03*
X363101Y693948D03*
X360990Y726862D03*
X358902Y739755D03*
X365547Y787015D03*
X363359Y797204D03*
X368830Y792479D03*
X359637Y986855D03*
X380930Y122022D03*
X379295Y131002D03*
X385720Y320902D03*
X376500Y366391D03*
Y378649D03*
X376770Y387272D03*
X390220Y392062D03*
X389920Y461362D03*
X387500Y495362D03*
X389020Y522862D03*
X374590Y736928D03*
X377987Y1297695D03*
X375030Y1325211D03*
X386827Y1429525D03*
X374900Y1534102D03*
X375430Y1676462D03*
X399240Y62722D03*
X404910Y62562D03*
X396294Y281585D03*
X395520Y448362D03*
X402500Y495362D03*
X394500Y522862D03*
X400589Y575236D03*
X399756Y813625D03*
X393156D03*
X399756Y807025D03*
X393156D03*
X406356Y813625D03*
Y807025D03*
X400888Y1395508D03*
X392947Y1397827D03*
X400924Y1408227D03*
X405946Y1408955D03*
X390777Y1435152D03*
X396946Y1537632D03*
X404920Y1539362D03*
X394360Y1616380D03*
X396824Y1673662D03*
X413459Y129061D03*
X420752Y239562D03*
X412720Y439362D03*
X417880Y461942D03*
X418520Y473562D03*
X412956Y813625D03*
Y807025D03*
X408339Y1325927D03*
X418320Y1383862D03*
X410933Y1384648D03*
X414909Y1395658D03*
X408915Y1402606D03*
X411150Y1408163D03*
X415856Y1420283D03*
X416926Y1426471D03*
X412416Y1431645D03*
X419302Y1434700D03*
X410074Y1424993D03*
X413599Y1441908D03*
X409140Y1566892D03*
X416020Y1620862D03*
X412456Y1649838D03*
X417960Y1650072D03*
X422650Y1653040D03*
X421320Y1671699D03*
X410249Y1673082D03*
X427120Y59862D03*
X428500Y65016D03*
Y70016D03*
X435340Y125346D03*
X429780Y153477D03*
X429395Y236562D03*
X428720Y439362D03*
X437720Y435362D03*
X437520Y476337D03*
X431220Y496362D03*
Y507143D03*
Y512623D03*
Y501643D03*
X425550Y924546D03*
X439104Y1324785D03*
X426320Y1383862D03*
X439030Y1383692D03*
X436467Y1391687D03*
X438458Y1402169D03*
X435570Y1398366D03*
X438645Y1426890D03*
X437299Y1436774D03*
X425030Y1434292D03*
X424820Y1552605D03*
X431620Y1541362D03*
X433350Y1579509D03*
X432200Y1607060D03*
X432500Y1613822D03*
X435500Y1646962D03*
X446640Y104552D03*
X443678Y145710D03*
X446746Y152662D03*
X442220Y323362D03*
X448220Y323582D03*
X450500Y358862D03*
X446730Y382432D03*
X443770Y371042D03*
X443300Y410962D03*
X447750Y414112D03*
X453020Y414262D03*
X443744Y429553D03*
X451421D03*
X442520Y476337D03*
Y484837D03*
X451520D03*
X453680Y515072D03*
X439427Y793255D03*
X449427D03*
X441836Y841835D03*
X448436D03*
X443842Y1389106D03*
X448020Y1391862D03*
X443424Y1397869D03*
X441369Y1394260D03*
X442970Y1406832D03*
X453805Y1396730D03*
X448114Y1396812D03*
X445230Y1411719D03*
X445723Y1419730D03*
X449778Y1441606D03*
X452520Y1564862D03*
X454661Y1609235D03*
X448181Y1614401D03*
X443800Y1610712D03*
X444940Y1641842D03*
X462320Y115948D03*
X466992Y145888D03*
X458264Y254862D03*
X461736Y306098D03*
X469830Y366158D03*
X456660Y359172D03*
X460800Y375362D03*
X455720Y404762D03*
X458600Y414262D03*
X466520Y475812D03*
X461520Y484837D03*
X457456Y522516D03*
X470880Y572692D03*
X467130Y600122D03*
X469427Y793255D03*
X459427D03*
X467436Y925602D03*
X456327Y926551D03*
X471437Y1294035D03*
X471545Y1325025D03*
X459321Y1396409D03*
X458441Y1414893D03*
X468880Y1418400D03*
X467400Y1556700D03*
X466520Y1574862D03*
X457220Y1603562D03*
X455681Y1622492D03*
X458978Y1634481D03*
X463344Y1637622D03*
X469580Y1640272D03*
X466460Y1672332D03*
X466180Y1678392D03*
X484396Y161364D03*
X476220Y158772D03*
X486720Y360862D03*
X482920Y398060D03*
X485020Y414162D03*
X480393Y429412D03*
X471920Y416687D03*
X474169Y476196D03*
X479169D03*
X482780Y607012D03*
X479427Y793255D03*
X474703Y925819D03*
X480587Y1294035D03*
X477968Y1548122D03*
X486210Y1547960D03*
X482400Y1558320D03*
X477905Y1659242D03*
X475150Y1654302D03*
X494112Y88040D03*
X503310Y113262D03*
X497800Y113562D03*
X500500Y117962D03*
X492150Y336810D03*
X498720Y360862D03*
X497568Y397632D03*
X489520Y411862D03*
X494020Y414262D03*
X502070Y424787D03*
X488070Y429412D03*
X493169Y476196D03*
X498169D03*
X493169Y484696D03*
X503218Y1337798D03*
X490307Y1421499D03*
X488920Y1408742D03*
X507335Y88862D03*
X510600Y92782D03*
X504700Y93862D03*
X513700Y117862D03*
X510900Y111962D03*
X519010Y147912D03*
X518186Y139821D03*
X514850Y168443D03*
X519236Y202404D03*
X518670Y219192D03*
X507160Y332452D03*
X514720Y360862D03*
X513720Y390362D03*
X513173Y408740D03*
X514637Y1426345D03*
X505777Y1425579D03*
X529720Y43054D03*
X534720Y42922D03*
X523978Y59074D03*
X529078Y59282D03*
X523220Y170362D03*
X534765Y161067D03*
X526920Y161362D03*
X529480Y183921D03*
X536127Y247652D03*
X531298Y284280D03*
X526980Y322582D03*
X521820Y336762D03*
X531720Y360862D03*
X535220Y383552D03*
X525720Y390362D03*
X528145Y408705D03*
X526941Y447802D03*
X532650Y442376D03*
Y450330D03*
Y454270D03*
X536000Y520362D03*
X524820Y545319D03*
X533167Y1329625D03*
Y1337025D03*
X528975Y1369724D03*
X535339Y1361318D03*
X533826Y1423065D03*
X524317Y1420335D03*
X542050Y47452D03*
X539720Y42862D03*
X550971Y42902D03*
X544720Y42892D03*
X548609Y48082D03*
X546100Y106162D03*
X546110Y100647D03*
X548942Y97821D03*
X544700Y112362D03*
X543083Y146338D03*
X548390Y236512D03*
X546390Y231742D03*
X539830Y274912D03*
X549220Y339687D03*
X546758Y360502D03*
X550024Y369123D03*
Y401023D03*
X551046Y878964D03*
X549757Y894025D03*
X545778Y948495D03*
X541378Y951944D03*
X541477Y976940D03*
X549177Y1010925D03*
X538209Y1027241D03*
X539914Y1049923D03*
X545371Y1041871D03*
X543914Y1049923D03*
X541167Y1329625D03*
Y1337025D03*
X549167D03*
Y1329625D03*
X542867Y1420245D03*
X565184Y47982D03*
X553650Y48842D03*
X562500Y104962D03*
X562300Y109962D03*
X562200Y114962D03*
X558900Y118962D03*
X564890Y142173D03*
X555220Y167937D03*
X561324Y301149D03*
X555520Y309827D03*
X557701Y369123D03*
X569080Y414002D03*
X559300Y422732D03*
X563700Y538477D03*
X566762Y882180D03*
X557947Y882255D03*
X558697Y891555D03*
X556697Y943475D03*
X565937Y968755D03*
X553332Y1026465D03*
X562700Y1022464D03*
X561157Y1029735D03*
X567343Y1041819D03*
X556151Y1037465D03*
X565849Y1346968D03*
X566510Y1352217D03*
X573190Y42912D03*
X575330Y47672D03*
X570208Y47982D03*
X579930Y72052D03*
X578900Y60362D03*
X573360Y140532D03*
X581175Y164717D03*
X569965Y161232D03*
X569470Y171702D03*
X579481Y194378D03*
X578450Y218562D03*
X578390Y225362D03*
X577676Y300268D03*
X570440Y331930D03*
X571830Y348772D03*
X570200Y372229D03*
X571720Y381862D03*
X577720D03*
X574491Y376549D03*
X581090Y426970D03*
X571930Y421232D03*
X571110Y442656D03*
Y446706D03*
X577220Y449462D03*
X583220Y493212D03*
X584173Y498422D03*
X577470Y505592D03*
X581147Y880067D03*
X575374Y889216D03*
X577622Y896854D03*
X583377Y901635D03*
X570657Y903335D03*
X580302Y908535D03*
X574007Y911355D03*
X570067Y921425D03*
X579229Y964343D03*
X580027Y1039100D03*
X586260Y52222D03*
X599800Y43152D03*
X597955Y48047D03*
X593369Y45682D03*
X590680Y83591D03*
X598295Y171862D03*
X599720Y184887D03*
X593220D03*
X595415Y246515D03*
X593763Y293999D03*
X588850Y291622D03*
X593120Y342782D03*
X586070Y352302D03*
X591720Y430787D03*
X595380Y416660D03*
X599220Y444362D03*
X597220Y458688D03*
X590210Y484132D03*
X589260Y519421D03*
X598503Y768931D03*
X600406Y882536D03*
X595572Y893190D03*
X600850Y902101D03*
X587617Y895115D03*
X592307Y1031185D03*
X594081Y1042722D03*
X599924Y1058989D03*
X586079Y1055076D03*
X591675Y1056610D03*
X601900Y1079662D03*
X611810Y34400D03*
X615530Y52792D03*
X614400Y46012D03*
X603063Y48023D03*
X606020Y84562D03*
X603720Y98362D03*
X608620Y94162D03*
X617409D03*
X602580Y151052D03*
X603019Y146399D03*
X606260Y161652D03*
X605350Y293092D03*
X605870Y298172D03*
X605560Y303372D03*
X607590Y314732D03*
X614130Y328762D03*
X605305Y331162D03*
X615180Y336812D03*
X605898Y372984D03*
X609690Y402812D03*
X604779Y423862D03*
X604360Y452120D03*
X609520Y515162D03*
X613220Y654662D03*
X603276Y741375D03*
X602768Y758385D03*
X608709Y769103D03*
X605555Y779324D03*
X603592Y1045812D03*
X609954Y1047613D03*
X614678Y1050637D03*
X605050Y1065867D03*
X612317Y1068895D03*
X626490Y51572D03*
X624860Y56712D03*
X625000Y43952D03*
X623300Y95762D03*
X620540Y100112D03*
X632300Y104472D03*
X627645Y236862D03*
X622730Y230362D03*
X629564Y256277D03*
X633150Y301457D03*
X627950Y298897D03*
X627600Y309134D03*
X632143Y306575D03*
X619474Y331162D03*
X622490Y402162D03*
X623220Y426362D03*
X625620Y447862D03*
Y442862D03*
X626400Y462812D03*
X625620Y457862D03*
Y452862D03*
X622860Y487310D03*
X623670Y507862D03*
X633000Y508700D03*
X628070Y760251D03*
X631231Y764219D03*
X632080Y1262074D03*
X626260Y1248762D03*
X628970Y1670880D03*
X643880Y42142D03*
X635800Y45762D03*
X647447Y46322D03*
X641200Y46762D03*
X637000Y68142D03*
X634500Y73422D03*
X645330Y77132D03*
X640220Y85542D03*
X634690D03*
X639901Y103462D03*
X640000Y108542D03*
X639970Y113892D03*
X635600Y151012D03*
X649870Y181942D03*
X645263Y235689D03*
X640295Y234237D03*
X636075Y389862D03*
X649075Y389937D03*
X638700Y400962D03*
X637220Y411362D03*
Y416362D03*
Y426362D03*
X640720Y452862D03*
X641235Y477377D03*
X640620Y483422D03*
X649218Y504277D03*
X642580Y508172D03*
X636960Y516002D03*
X648296Y528255D03*
X640785Y952415D03*
Y959265D03*
X647689Y997251D03*
X647690Y1260812D03*
X637041Y1248685D03*
X642548Y1248785D03*
X649197Y1251276D03*
X643725Y1643467D03*
X648225Y1658482D03*
X642725Y1658562D03*
X635410Y1664220D03*
X637540Y1669480D03*
X645725Y1691182D03*
X640725Y1691452D03*
X650725Y1690682D03*
X642225Y1708457D03*
X648220Y1716912D03*
X636160Y1710662D03*
X648220Y1722921D03*
X651680Y73812D03*
X656500Y69662D03*
X661587D03*
X661600Y75562D03*
X656426Y75431D03*
X652320Y123362D03*
X651730Y177212D03*
X659877Y188372D03*
X659871Y192372D03*
X660490Y200172D03*
X652000Y402362D03*
X653100Y407862D03*
X654780Y422722D03*
X654510Y431362D03*
X659970Y419602D03*
X654300Y447002D03*
X664990Y454252D03*
X655820Y452662D03*
X655800Y461432D03*
X662480Y449782D03*
X662500Y467030D03*
X664140Y475362D03*
X657740Y473132D03*
X665610Y482662D03*
X661865Y505334D03*
X656877Y514716D03*
X665990Y517131D03*
X661220Y526862D03*
X650794Y515039D03*
X664630Y1259442D03*
X664709Y1249918D03*
X661400Y1263522D03*
X651725Y1643397D03*
X677560Y40572D03*
X672250Y40812D03*
X682290Y46822D03*
X674035Y74522D03*
X677820Y89462D03*
X680578Y75992D03*
X674540Y80652D03*
X670800Y85932D03*
X667940Y80142D03*
X671320Y91192D03*
X673720Y110362D03*
X668300Y132400D03*
X673713Y237725D03*
X683100Y369550D03*
X670940Y406452D03*
X681610Y446062D03*
X675220Y508862D03*
X680220D03*
X673340Y530922D03*
X676535Y769812D03*
X670485Y952415D03*
Y959265D03*
X676309Y994386D03*
X678683Y1254408D03*
X672188Y1248885D03*
X677980Y1262074D03*
X672773Y1404136D03*
X682160Y1548040D03*
X678621Y1571072D03*
X678619Y1579070D03*
X673420Y1650057D03*
X671610Y1673792D03*
X675120Y1716242D03*
X672270Y1721612D03*
X687120Y39632D03*
X692289Y40633D03*
X696800Y42108D03*
X696838Y47940D03*
X683440Y42832D03*
X687344Y46940D03*
X692389Y46439D03*
X690027Y70142D03*
X699475Y69982D03*
X688019Y109845D03*
X687034Y115896D03*
X692083Y128157D03*
X697615Y123697D03*
X698900Y135782D03*
X687238Y171071D03*
X690520Y399622D03*
X685220Y391652D03*
X694880Y412255D03*
X693300Y418362D03*
X685220Y495887D03*
X697972Y481734D03*
X695220Y495887D03*
X690220D03*
X695220Y508862D03*
X690330Y503530D03*
X695220Y516852D03*
X699040Y952592D03*
X698920Y959252D03*
X697533Y1252541D03*
X694100Y1261562D03*
X699186Y1246192D03*
X692233Y1252480D03*
X696810Y1300162D03*
X692280Y1302532D03*
X692100Y1567190D03*
X686220Y1640667D03*
X697595Y1666862D03*
X701838Y42202D03*
Y47940D03*
X712340Y128093D03*
X707008Y125804D03*
X715600Y363900D03*
X705700Y361400D03*
X711200Y396500D03*
X713220Y388362D03*
X707330Y406232D03*
X712781Y420381D03*
X702940Y486652D03*
X701757Y521324D03*
X711220Y516852D03*
X705220Y530362D03*
X710417Y773685D03*
X701087Y988721D03*
X708090Y1262074D03*
X703790Y1249622D03*
X709748Y1252004D03*
X708126Y1403331D03*
X712222Y1570703D03*
X711102Y1575683D03*
X712582Y1584843D03*
X715775Y1599024D03*
X706103Y1617107D03*
X708857Y1613462D03*
X710570Y1629890D03*
X708830Y1623115D03*
X708999Y1646762D03*
X703719Y1646768D03*
X700460Y1660918D03*
X709678Y1658485D03*
X704759Y1677001D03*
X724620Y40062D03*
X728720Y43562D03*
X719820Y45862D03*
X729933Y108388D03*
X722500Y365500D03*
X727000D03*
X731400D03*
X725220Y380787D03*
X722500Y374100D03*
X727000D03*
X731400Y375000D03*
X728220Y388362D03*
X725280Y406242D03*
X721873Y421132D03*
X723220Y508882D03*
X717220D03*
X729220D03*
X729212Y531700D03*
X720240Y598292D03*
X729885Y952415D03*
Y959265D03*
X723975Y984675D03*
X723037Y1045285D03*
X731467Y1045015D03*
X723850Y1235892D03*
X723700Y1258727D03*
X722792Y1248688D03*
X728977Y1574453D03*
X717402Y1574433D03*
X723942Y1574123D03*
X729052Y1602518D03*
X726092Y1598483D03*
X720987Y1599568D03*
X718758Y1673800D03*
X745900Y40362D03*
X733314Y40862D03*
X740100Y41162D03*
X746100Y46262D03*
X736620Y45262D03*
X742960Y76142D03*
X733879Y83664D03*
X737929Y83714D03*
X736720Y101662D03*
X745035Y94632D03*
X735770Y94988D03*
X739823Y91052D03*
X741308Y108742D03*
X740220Y145362D03*
X732720Y231362D03*
X745685Y269322D03*
X741800Y363200D03*
X735800Y365500D03*
X732700Y351500D03*
X740200Y375100D03*
X735800Y375000D03*
X733220Y388362D03*
X733590Y406242D03*
X742450Y431472D03*
X738670Y417482D03*
X743980Y443482D03*
X742360Y436662D03*
X740510Y465258D03*
X741420Y494162D03*
X745700Y492062D03*
X747600Y506592D03*
X735220Y508862D03*
X745220Y522362D03*
X735173Y521362D03*
X740909Y754975D03*
X736425Y770072D03*
X738638Y1253541D03*
X737580Y1262074D03*
X740840Y1655590D03*
X750700Y106642D03*
X754800Y97082D03*
X757340Y92562D03*
X762590Y274028D03*
X758412Y298790D03*
X758390Y307272D03*
X749650Y398532D03*
X748380Y429052D03*
X757365Y459862D03*
X752500Y495762D03*
X757238Y483862D03*
X751220Y522362D03*
X755940Y516862D03*
X756650Y526072D03*
X761710Y517651D03*
X762570Y756052D03*
X751997Y952481D03*
Y959331D03*
X751505Y987865D03*
X751957Y1041755D03*
X759237Y1253019D03*
X753000Y1261352D03*
X759149Y1247626D03*
X753656Y1250281D03*
X748630Y1251792D03*
X751927Y1301285D03*
X757720Y1375462D03*
Y1384062D03*
X758020Y1397862D03*
X758420Y1406862D03*
X758120Y1414762D03*
X749612Y1579023D03*
X749652Y1586407D03*
X749612Y1594683D03*
X758360Y1589661D03*
X750504Y1612521D03*
X758830Y1674823D03*
X751620Y1674312D03*
X763994Y1674691D03*
X774059Y68912D03*
X764850Y249792D03*
X766320Y264892D03*
X768490Y354942D03*
X774490D03*
X773245Y398212D03*
Y403212D03*
Y408212D03*
X771050Y416940D03*
X766195Y428212D03*
X772365Y454862D03*
Y459862D03*
X765810Y506342D03*
X769745Y502600D03*
X775378Y502502D03*
X766125Y770072D03*
X767080Y1262074D03*
X767053Y1251480D03*
X776922Y1590444D03*
X766811Y1661726D03*
X766603Y1721797D03*
X790120Y135412D03*
X795520Y393462D03*
X781320Y398212D03*
X787320Y444862D03*
Y439862D03*
Y454862D03*
Y449862D03*
Y459862D03*
X787360Y469862D03*
X796315Y469290D03*
X783340Y474802D03*
X782690Y488862D03*
X785800Y482762D03*
X783600Y502462D03*
X783450Y522462D03*
X791969Y618384D03*
X794658Y770104D03*
X789385Y952415D03*
Y959265D03*
X789877Y987865D03*
X783130Y1259372D03*
X794157Y1248685D03*
X788890Y1248688D03*
X796880Y1262074D03*
X796280Y1254402D03*
X797052Y1611893D03*
X801840Y276587D03*
X802070Y284092D03*
X805775Y297007D03*
X805570Y307622D03*
X802220Y393727D03*
X800352Y408389D03*
X803120Y428762D03*
X797720Y428412D03*
X798370Y439932D03*
X802790Y433832D03*
X801750Y444330D03*
X802810Y454862D03*
Y464862D03*
Y449862D03*
Y459862D03*
X802865Y474862D03*
X810815D03*
X812510Y486422D03*
X801567Y512942D03*
X810850Y770272D03*
X812440Y1258727D03*
X801935Y1252215D03*
X811521Y1248688D03*
X806323Y1343076D03*
X812130Y1343022D03*
X812652Y1577793D03*
X801652Y1584539D03*
X814570Y145952D03*
X814531Y139851D03*
X820900Y147112D03*
X825003Y389012D03*
X819220Y412264D03*
X821720Y428437D03*
X816810Y464862D03*
X816400Y472900D03*
X821720Y511082D03*
Y527082D03*
X815650Y516807D03*
X826497Y739255D03*
X826930Y752352D03*
X825425Y770072D03*
X819085Y952415D03*
Y959265D03*
X819577Y987865D03*
X826750Y1262074D03*
X824268Y1256206D03*
X825256Y1249197D03*
X836779Y68008D03*
X839898Y87248D03*
X841584Y94181D03*
X845220Y135862D03*
Y129362D03*
X837160Y218212D03*
Y213207D03*
X844526Y204968D03*
X838820Y206872D03*
X844250Y301629D03*
X844100Y309306D03*
X838784Y392880D03*
X838220Y459562D03*
X838645Y492862D03*
X832590Y512888D03*
X829745Y498082D03*
X834327Y769285D03*
X840851Y1229802D03*
X845240Y1242372D03*
X842630Y1256912D03*
X841747Y1246745D03*
X832090Y1326862D03*
X839052Y1611893D03*
X850015Y87341D03*
X847472Y94754D03*
X860050Y215310D03*
X847580Y232222D03*
X861865Y273730D03*
X856243Y286447D03*
X859920Y308852D03*
X859740Y399081D03*
X856842Y410760D03*
X846490Y422131D03*
X857560Y417762D03*
X850610Y444352D03*
X857620Y492862D03*
X848620Y509752D03*
X853070Y515447D03*
X860345Y522162D03*
X848685Y952415D03*
Y959265D03*
X849177Y987865D03*
X851867Y1256798D03*
X875169Y185113D03*
X873200Y194262D03*
X877971Y196652D03*
X867528Y231788D03*
X867700Y268262D03*
X863747Y280870D03*
X867237Y273325D03*
X868552Y285537D03*
X868113Y409372D03*
X862320Y431462D03*
X863415Y445829D03*
X868110Y499142D03*
X866820Y736562D03*
X883909Y281862D03*
X879587Y270004D03*
X883870Y272652D03*
X887338Y296760D03*
X893440Y336232D03*
X890820Y389362D03*
X887810Y582442D03*
X885310Y736442D03*
X884619Y916477D03*
X892317Y915872D03*
X888652Y1597793D03*
Y1609793D03*
X896540Y341132D03*
X900490Y482752D03*
X899049Y501792D03*
X896652Y1605793D03*
X922726Y176302D03*
X922100Y181791D03*
X917386Y184114D03*
X923836Y193563D03*
X927034Y445594D03*
X914300Y486862D03*
X911361Y508201D03*
X920070Y966320D03*
X917980Y974952D03*
X914838Y985989D03*
X926120Y1671500D03*
X914500Y1671400D03*
X940424Y184190D03*
X936424D03*
X940410Y188852D03*
X931580Y472092D03*
X937000Y489179D03*
X935052Y812630D03*
X927790Y966450D03*
X939740Y987762D03*
X933700Y1671500D03*
X957020Y264862D03*
X947100Y374462D03*
X946300Y392562D03*
X950660Y399472D03*
X949920Y404602D03*
X945100Y534464D03*
X957220Y582862D03*
X949560Y981392D03*
X946100Y1671800D03*
X962570Y282812D03*
X962882Y314512D03*
X963854Y320113D03*
X974026Y398056D03*
X975670Y392063D03*
X971600Y408602D03*
X963720Y439862D03*
X969351Y512416D03*
X965904Y1554364D03*
X960904D03*
X962086Y1603984D03*
X990501Y152397D03*
X986369Y155358D03*
X985499Y168753D03*
X990115Y173039D03*
X987259Y276094D03*
X978000Y362462D03*
X988723Y369650D03*
X986400Y383123D03*
X983770Y373962D03*
X979766Y377507D03*
X977949Y384205D03*
X980856Y392502D03*
X983629Y397628D03*
X991369Y408252D03*
X979240Y425212D03*
X989635Y426655D03*
X980720Y512362D03*
X992306Y1295049D03*
X984270Y1554364D03*
X995180Y153689D03*
X1001101Y165510D03*
X996415Y172579D03*
X1002920Y174799D03*
X1008120Y198293D03*
X1000610Y211039D03*
X1005640Y210969D03*
X994743Y289843D03*
X993901Y376544D03*
X1006201Y370004D03*
X999440Y371782D03*
X996922Y367764D03*
X1005123Y414662D03*
X997617Y412383D03*
X997225Y419162D03*
X1005720Y498862D03*
X1005520Y510932D03*
X1008560Y589682D03*
X1007444Y766798D03*
X1001970Y1251522D03*
X1002070Y1256942D03*
X1006897Y1262435D03*
X1007636Y1554364D03*
X993698Y1604000D03*
X1011320Y202169D03*
X1017360Y199109D03*
X1019355Y218423D03*
X1010005Y208424D03*
X1010470Y224169D03*
X1022957Y249528D03*
X1024720Y259662D03*
X1017547Y255928D03*
X1014500Y266862D03*
X1021118Y294290D03*
X1015520Y302862D03*
X1009800Y343800D03*
X1009883Y367955D03*
X1010420Y416062D03*
X1019300Y405662D03*
X1024200Y510362D03*
X1020392Y521826D03*
X1016360Y594682D03*
X1019000Y601042D03*
X1021654Y606302D03*
X1023203Y989083D03*
X1023012Y1245659D03*
X1015170Y1249722D03*
X1022835Y1252034D03*
X1032547Y247928D03*
Y255928D03*
X1037618Y261200D03*
X1025862Y291727D03*
X1032260Y294532D03*
X1036278Y307393D03*
X1026250Y381582D03*
X1039340Y372642D03*
X1025004Y374662D03*
X1031153Y390152D03*
X1039370Y413842D03*
Y418842D03*
X1038294Y506504D03*
X1032155Y509737D03*
X1025530Y519627D03*
X1033040Y519852D03*
X1038130Y518417D03*
X1040720Y591862D03*
X1029630Y601252D03*
X1037144Y766798D03*
X1032063Y950820D03*
X1032527Y959265D03*
X1030830Y1261302D03*
X1030270Y1256042D03*
X1031002Y1554364D03*
X1025298Y1604000D03*
X1044978Y267275D03*
Y275275D03*
X1043720Y363462D03*
X1047010Y1259222D03*
X1057047Y1256865D03*
X1055531Y1248688D03*
X1044930Y1263492D03*
X1054368Y1554364D03*
X1056898Y1604000D03*
X1059978Y267275D03*
Y283275D03*
Y275275D03*
X1072310Y364422D03*
X1062120Y477462D03*
X1058220Y585862D03*
X1061867Y774038D03*
X1062123Y950460D03*
X1062227Y959265D03*
X1061837Y994357D03*
X1061330Y1262074D03*
X1059410Y1252272D03*
X1059086Y1579240D03*
X1085300Y282162D03*
X1077270Y374131D03*
X1076598Y477087D03*
X1081930Y477132D03*
X1076739Y506461D03*
X1077751Y522235D03*
X1084376Y774754D03*
X1084239Y952481D03*
X1084703Y960926D03*
X1079367Y984535D03*
X1084140Y1245202D03*
X1076520Y1259072D03*
X1086613Y1256826D03*
X1074010Y1510650D03*
X1077734Y1554364D03*
X1105580Y132822D03*
X1100630Y130376D03*
X1105553Y356475D03*
X1095199Y768537D03*
X1097749Y779005D03*
X1093172Y1011260D03*
X1104601Y1244631D03*
X1091000Y1262074D03*
X1106200Y1250162D03*
X1103530Y1263602D03*
X1105480Y1517982D03*
X1101600Y1554364D03*
X1104750Y1549346D03*
X1103960Y1576300D03*
Y1583300D03*
Y1590300D03*
X1092436Y1603944D03*
X1118486Y208942D03*
X1111918Y234718D03*
X1120190Y255652D03*
X1121523Y950460D03*
X1121627Y959265D03*
X1121237Y994357D03*
X1114448Y1245353D03*
X1120920Y1246282D03*
X1120800Y1262074D03*
X1106740Y1267902D03*
X1110725Y1518046D03*
X1115802Y1615010D03*
X1117182Y1625460D03*
X1114150Y1715726D03*
X1132547Y64864D03*
X1129997Y69864D03*
X1128485Y198159D03*
X1124360Y259712D03*
X1125409Y305797D03*
X1124120Y643762D03*
X1136720Y641362D03*
X1125194Y768709D03*
X1131721Y1439984D03*
X1127377Y1628485D03*
X1147700Y362731D03*
X1140465Y379592D03*
X1147700Y368041D03*
X1140912Y602207D03*
X1152241Y766798D03*
X1151223Y950460D03*
X1151327Y959265D03*
X1140727Y985255D03*
X1144577Y1244341D03*
X1139796Y1248338D03*
X1144792Y1249984D03*
X1150400Y1262074D03*
X1148563Y1257097D03*
X1152397Y1301095D03*
X1153465Y1550301D03*
X1140750Y1604330D03*
X1139392Y1620851D03*
X1159460Y194090D03*
X1159753Y361281D03*
X1156790Y373231D03*
X1157980Y588892D03*
X1158020Y593812D03*
X1158030Y598952D03*
X1158047Y609052D03*
X1158054Y603965D03*
X1159078Y763401D03*
X1158997Y1301095D03*
X1165597D03*
X1170670Y1439635D03*
X1163308Y1524187D03*
X1155433D03*
X1169213Y1550301D03*
X1161339D03*
X1169460Y1606630D03*
Y1616630D03*
Y1611630D03*
X1164830Y1628830D03*
Y1645632D03*
X1169325Y1642600D03*
X1158325D03*
X1162383Y1652505D03*
X1161613Y1669112D03*
X1187413Y143132D03*
X1181420Y157962D03*
X1181700Y186962D03*
X1173314Y176452D03*
X1181470Y208802D03*
X1181500Y222162D03*
X1172795Y222174D03*
X1186653Y302242D03*
X1174120Y355362D03*
X1180923Y950460D03*
X1181027Y959265D03*
X1180637Y994357D03*
X1179080Y1260672D03*
X1174331Y1248688D03*
X1177222Y1255567D03*
X1179180Y1265872D03*
X1172197Y1301095D03*
X1184200Y1599900D03*
X1185030Y1624660D03*
X1186830Y1645632D03*
X1175830D03*
X1180325Y1642600D03*
X1173383Y1652505D03*
X1184383D03*
X1183613Y1669112D03*
X1172613D03*
X1193532Y132644D03*
X1196930Y126690D03*
X1194800Y143112D03*
X1197414Y161592D03*
X1191020Y170862D03*
X1194840Y240672D03*
X1192877Y595012D03*
X1201977Y593252D03*
X1197280Y610352D03*
X1192890Y600292D03*
X1192887Y605652D03*
X1202495Y961858D03*
X1201627Y955185D03*
X1201403Y989083D03*
X1195097Y1251575D03*
X1193590Y1267912D03*
X1195470Y1262802D03*
X1194842Y1373682D03*
X1194442Y1380612D03*
X1203832Y1409772D03*
Y1419772D03*
X1187830Y1522188D03*
X1198546Y1524688D03*
X1187720Y1536362D03*
X1198485Y1534313D03*
X1187720Y1553692D03*
Y1544292D03*
X1198436Y1551192D03*
Y1561062D03*
X1187720Y1563182D03*
X1201600Y1633790D03*
X1197400Y1645942D03*
X1190895Y1642910D03*
X1194183Y1669422D03*
X1197240Y1691422D03*
X1190735Y1688390D03*
X1194793Y1698295D03*
X1201505Y1688435D03*
X1194023Y1714902D03*
X1215763Y114363D03*
X1206114Y132962D03*
X1206694Y139512D03*
X1213420Y144962D03*
X1214415Y153962D03*
X1214054Y186092D03*
X1208518Y174162D03*
X1213720Y195362D03*
X1215720Y204862D03*
X1219060Y213312D03*
X1206660Y224742D03*
X1213540Y224792D03*
X1207220Y247148D03*
X1210900Y265300D03*
X1205165Y380962D03*
X1218870Y418082D03*
X1214000Y599262D03*
X1208980Y598462D03*
X1212407Y773625D03*
X1209457Y787702D03*
X1204161Y1244598D03*
X1209790Y1259423D03*
X1204305Y1254514D03*
X1208750Y1266546D03*
X1210457Y1658415D03*
X1205820Y1652910D03*
X1213980Y1676500D03*
X1217210Y1684520D03*
X1218810Y1691732D03*
X1208010Y1691467D03*
X1212305Y1688700D03*
X1216363Y1698605D03*
X1205563Y1698340D03*
X1215593Y1715212D03*
X1204793Y1714947D03*
X1225100Y91500D03*
X1223500Y111162D03*
X1229500Y125100D03*
X1225574Y188662D03*
X1225320Y200162D03*
X1233780Y214572D03*
X1232000Y248332D03*
X1230720Y380362D03*
X1224300Y380400D03*
X1224439Y956561D03*
X1231327Y955185D03*
X1224031Y988295D03*
X1232107Y1057940D03*
X1228500Y1242102D03*
X1235234Y1256802D03*
X1224007Y1251715D03*
X1244200Y112862D03*
X1249362Y111600D03*
X1237664Y141202D03*
X1249430Y147620D03*
X1241100Y145842D03*
X1246272Y164889D03*
X1243100Y160181D03*
X1249720Y177662D03*
X1242470Y173612D03*
X1243184Y182422D03*
X1248868Y213414D03*
X1246853Y208229D03*
X1245593Y237462D03*
X1240500Y244332D03*
X1252040Y306480D03*
X1246079Y876083D03*
X1251727Y907485D03*
X1244237Y928847D03*
X1250230Y933374D03*
X1244383Y939465D03*
X1247301Y1022801D03*
X1247044Y1065220D03*
X1248000Y1089723D03*
X1239435Y1248688D03*
X1246654Y1660152D03*
X1267014Y112012D03*
X1266926Y118057D03*
X1254520Y115562D03*
X1253161Y128848D03*
X1256093Y149462D03*
X1265010Y162222D03*
X1261899Y174648D03*
X1263830Y195682D03*
X1252720Y193362D03*
X1267315Y220701D03*
X1252930Y205462D03*
X1259703Y209808D03*
X1253440Y230552D03*
X1253860Y235622D03*
X1253950Y246692D03*
X1266715Y244692D03*
X1254370Y241302D03*
X1265065Y249982D03*
X1258250Y292986D03*
X1263150Y294726D03*
X1267150Y305998D03*
X1256220Y434362D03*
X1261220Y454362D03*
X1253220Y451362D03*
X1267220D03*
X1255920Y511362D03*
X1261607Y853715D03*
X1265003Y860128D03*
X1254788Y873600D03*
X1262954Y873559D03*
X1258891Y881517D03*
X1264570Y891259D03*
X1256097Y914995D03*
X1267447Y912265D03*
X1252880Y924465D03*
X1260887Y935665D03*
X1254166Y942501D03*
X1253087Y978815D03*
X1260502Y1015250D03*
X1264362Y1048399D03*
X1267471Y1060464D03*
X1253916Y1051209D03*
X1253863Y1071764D03*
X1265784Y1076853D03*
X1260341Y1067280D03*
X1259335Y1074313D03*
X1265387Y1083345D03*
X1253557Y1086495D03*
X1257586Y1334649D03*
X1259433Y1660486D03*
X1275820Y87962D03*
X1269420Y96012D03*
X1271284Y108971D03*
X1278949Y123567D03*
X1282764Y135398D03*
X1269228Y147097D03*
X1277820Y140682D03*
X1281093Y144516D03*
X1277490Y165946D03*
X1271954Y159143D03*
X1271593Y165962D03*
X1276952Y174834D03*
X1278093Y184462D03*
X1278183Y201262D03*
X1272893Y191262D03*
X1271315Y220701D03*
X1284383Y215762D03*
X1284746Y207271D03*
X1277355Y216851D03*
X1273093Y213962D03*
X1280134Y235206D03*
X1277749Y230871D03*
X1277661Y225685D03*
X1278783Y221386D03*
X1282654Y226309D03*
X1276800Y276562D03*
X1269960Y294536D03*
X1272530Y429362D03*
X1284220D03*
X1280270Y434362D03*
X1272220D03*
X1278380Y463362D03*
X1276220Y477362D03*
X1283220D03*
X1277266Y868490D03*
X1278043Y862242D03*
X1271410Y866886D03*
X1270912Y877372D03*
X1270249Y885331D03*
X1271402Y904801D03*
X1278764Y1015609D03*
X1277461Y1041864D03*
X1284922Y1038464D03*
X1277419Y1062985D03*
X1283822Y1055804D03*
X1275830Y1056275D03*
X1271087Y1093050D03*
X1270528Y1100231D03*
X1275528D03*
X1272550Y1347922D03*
X1269012Y1371693D03*
X1274548Y1660486D03*
X1293454Y81232D03*
X1298640Y93062D03*
X1292880Y93162D03*
X1292899Y98519D03*
X1297884Y120072D03*
X1294751Y133852D03*
X1288093Y125962D03*
X1291478Y137745D03*
X1286150Y131092D03*
X1291311Y152073D03*
X1300481Y151020D03*
X1286513Y161483D03*
X1290734Y199122D03*
X1285899Y196392D03*
X1291194Y188899D03*
X1288904Y204002D03*
X1289739Y218499D03*
X1291983Y208562D03*
X1285393Y222262D03*
X1292554Y230101D03*
X1301235Y228210D03*
X1285710Y249182D03*
X1290293Y247562D03*
X1288637Y240448D03*
X1292630Y240462D03*
X1298032Y267219D03*
X1295540Y440902D03*
X1301310Y440862D03*
X1291220Y463362D03*
X1294440Y477267D03*
X1300220Y477362D03*
X1299327Y765475D03*
X1297298Y790982D03*
X1285316Y865291D03*
X1295535Y871113D03*
X1298830Y864461D03*
X1292792Y928724D03*
X1288257Y921605D03*
X1296637Y970755D03*
X1300851Y1043664D03*
X1296478Y1064139D03*
X1298540Y1056104D03*
X1291775Y1055990D03*
X1288529Y1069460D03*
X1288000Y1362151D03*
X1296930Y1660520D03*
X1311260Y83032D03*
X1314406Y97756D03*
X1308274Y104162D03*
X1310000Y113552D03*
X1302080Y117032D03*
X1302509Y134795D03*
X1308825Y136721D03*
X1315353Y146030D03*
X1310880Y143431D03*
X1315020Y139762D03*
X1305115Y142712D03*
X1309049Y182865D03*
X1309918Y201187D03*
X1314970Y219772D03*
X1306190Y210502D03*
X1309189Y206274D03*
X1316842Y238692D03*
X1317300Y250162D03*
X1316754Y268442D03*
X1317100Y553900D03*
X1303576Y659671D03*
X1305187Y735630D03*
X1304707Y769984D03*
X1307627Y764735D03*
X1314227Y770855D03*
X1301927Y759935D03*
X1305117Y797125D03*
X1311407Y868055D03*
X1307717Y888265D03*
X1311798Y1054354D03*
X1305878Y1062943D03*
X1317150Y1062622D03*
X1316092Y1053513D03*
X1307032Y1058856D03*
X1311780Y1058894D03*
X1311952Y1321945D03*
X1304066Y1323578D03*
X1309194Y1655255D03*
X1313583Y1660466D03*
X1322248Y68487D03*
X1322415Y75480D03*
X1322906Y94212D03*
X1319968Y98266D03*
X1322906Y109733D03*
X1321747Y136899D03*
X1326826Y138922D03*
X1332002Y142289D03*
X1326974Y144338D03*
X1320880Y143430D03*
X1332654Y154452D03*
X1332268Y159982D03*
X1329620Y227682D03*
X1323912Y245111D03*
X1323694Y266442D03*
X1320387Y258901D03*
X1325769Y259001D03*
X1328745Y732336D03*
X1323345Y769844D03*
X1332947Y767085D03*
X1320032Y775725D03*
X1320786Y1339353D03*
X1318151Y1655269D03*
X1333709Y1655241D03*
X1329331Y1660390D03*
X1341718Y130781D03*
X1348079Y129474D03*
X1336819Y150298D03*
X1339481Y154705D03*
X1343034Y141698D03*
X1337547Y170397D03*
X1337637Y162994D03*
X1337697Y728652D03*
X1338495Y774984D03*
X1345079Y1660508D03*
X1366369Y83820D03*
X1364844Y133782D03*
X1363266Y155703D03*
X1357514Y150092D03*
X1351165Y150861D03*
X1353894Y144872D03*
X1362564Y161142D03*
X1363170Y200872D03*
X1355250Y211002D03*
X1356220Y581862D03*
X1361727Y680665D03*
X1351554Y1325594D03*
X1364860Y1455172D03*
X1375619Y236261D03*
X1374054Y223752D03*
X1378684Y229122D03*
X1381094Y224412D03*
X1370207Y682245D03*
X1369297Y807025D03*
X1375897Y813625D03*
X1382497Y807025D03*
X1370577Y1421899D03*
X1382157Y1408975D03*
X1377075Y1425014D03*
X1386684Y145017D03*
X1386404Y149008D03*
X1394182Y171470D03*
X1398182D03*
X1389097Y813625D03*
X1384638Y1325516D03*
X1396311Y1385712D03*
X1398680Y1380582D03*
X1387074Y1384272D03*
X1390513Y1395452D03*
X1387066Y1401734D03*
X1387291Y1408163D03*
X1392400Y1419825D03*
X1390170Y1423942D03*
X1388557Y1431645D03*
X1395443Y1434700D03*
X1383429Y1427652D03*
X1389220Y1446708D03*
X1391655Y1570037D03*
X1391055Y1565037D03*
X1393000Y1590300D03*
X1401971Y924341D03*
X1401655Y1384676D03*
X1415171Y1383692D03*
X1412608Y1391687D03*
X1414362Y1402191D03*
X1414786Y1426890D03*
X1413440Y1436774D03*
X1409680Y1430613D03*
X1401371Y1434592D03*
X1403350Y1516435D03*
X1400695Y1570037D03*
X1400715Y1565037D03*
X1401300Y1619917D03*
X1400000Y1626362D03*
X1410500Y1638862D03*
X1431430Y251265D03*
X1430097Y726635D03*
X1419697Y792165D03*
X1429697D03*
X1418030Y1325927D03*
X1418990Y1387452D03*
X1415620Y1396652D03*
X1419055Y1392497D03*
X1418870Y1406742D03*
X1423256Y1403728D03*
X1424255Y1396612D03*
X1421371Y1411719D03*
X1421864Y1419730D03*
X1426020Y1521535D03*
X1427120Y1537355D03*
X1427320Y1548575D03*
X1416800Y1564862D03*
X1425620Y1556662D03*
X1428403Y1581378D03*
X1416060Y1574922D03*
X1436335Y309407D03*
X1436050Y321352D03*
X1432487Y712485D03*
X1440150Y730182D03*
X1438457Y737565D03*
X1439697Y792165D03*
X1441357Y845635D03*
X1444874Y925533D03*
X1436470Y925622D03*
X1432125Y924530D03*
X1446807Y1293335D03*
Y1301335D03*
X1444997Y1392885D03*
X1435462Y1396409D03*
X1443112Y1417929D03*
X1445020Y1412672D03*
X1443676Y1432624D03*
X1439742Y1436924D03*
X1434720Y1454862D03*
X1440440Y1454892D03*
X1436330Y1521152D03*
X1436570Y1536972D03*
X1436720Y1548192D03*
X1437140Y1576012D03*
X1446700Y1598400D03*
X1438320Y1668292D03*
X1438220Y1673955D03*
X1446715Y1679957D03*
X1462561Y205982D03*
X1459900Y370823D03*
X1463600Y374462D03*
X1449777Y371039D03*
X1449697Y792165D03*
X1459697D03*
X1454557Y845635D03*
X1450997Y925673D03*
X1448586Y1325395D03*
X1461062Y1413246D03*
X1448620Y1556162D03*
X1448920Y1675062D03*
X1464200Y67802D03*
X1473090Y204502D03*
X1476858Y225448D03*
X1466958Y244948D03*
X1474660Y252878D03*
X1473820Y265962D03*
X1466660Y273878D03*
X1468400Y283709D03*
X1472261Y300182D03*
X1470073Y316202D03*
X1470841Y721493D03*
X1474000Y739362D03*
X1480250Y757753D03*
X1473717Y744674D03*
X1467587Y770665D03*
X1479870Y763842D03*
X1480320Y1338759D03*
X1466448Y1421499D03*
X1470487Y1462965D03*
X1478320Y1522962D03*
X1478061Y1633864D03*
X1493120Y240412D03*
X1490029Y309277D03*
X1494784Y374188D03*
X1486040Y368392D03*
X1493384Y411313D03*
X1482650Y411190D03*
X1495527Y406215D03*
X1489310Y426822D03*
X1494968Y732603D03*
X1489387Y757925D03*
X1491828Y766875D03*
X1486997Y1392015D03*
Y1402015D03*
X1493967Y1418445D03*
X1481918Y1425579D03*
X1482830Y1525162D03*
X1493700Y1665900D03*
X1512420Y239116D03*
X1498984Y282797D03*
X1497817Y292997D03*
Y300997D03*
Y308997D03*
X1505922Y304583D03*
X1505297Y671325D03*
X1508067Y664655D03*
X1496813Y757699D03*
X1510557Y747202D03*
X1502745Y759915D03*
X1512483Y1043233D03*
X1512587Y1323205D03*
Y1333205D03*
X1511357Y1361195D03*
X1510027Y1425825D03*
X1522920Y113030D03*
X1518575Y138662D03*
X1526675Y140117D03*
X1526083Y146225D03*
X1514520Y231116D03*
X1525977Y293444D03*
Y301444D03*
X1517669Y291516D03*
X1518017Y757455D03*
X1526000Y745162D03*
X1523197Y759045D03*
X1518967Y891005D03*
X1520528Y917924D03*
X1527257Y917665D03*
X1522907Y986792D03*
X1523614Y1011464D03*
X1515770Y1028159D03*
X1521528Y1031364D03*
X1526427Y1019785D03*
X1522746Y1048368D03*
X1526746D03*
X1520737Y1061993D03*
X1525787Y1323205D03*
Y1333205D03*
X1516137Y1432135D03*
X1544010Y27552D03*
X1535320Y113062D03*
X1529500Y122122D03*
X1529233Y153162D03*
X1535450Y155262D03*
X1542401Y141561D03*
X1545447Y156035D03*
X1537262Y197834D03*
X1533247Y284324D03*
X1533977Y293444D03*
Y301444D03*
X1540989Y616587D03*
X1541211Y646178D03*
X1530185Y757790D03*
X1531403Y765791D03*
X1540426Y855555D03*
X1540800Y889012D03*
X1531827Y913665D03*
X1535622Y905170D03*
X1544993Y936489D03*
X1543042Y951465D03*
X1535580Y948056D03*
X1536837Y965965D03*
X1530847Y978075D03*
X1532107Y971957D03*
X1538393Y1016271D03*
X1545047Y1030225D03*
X1540227Y1027095D03*
X1543727Y1021175D03*
X1535797Y1037875D03*
X1530467Y1045234D03*
X1536273Y1046561D03*
X1544337Y1042125D03*
X1543667Y1049835D03*
X1532288Y1052545D03*
X1531011Y1660548D03*
X1554239Y138263D03*
X1552960Y124359D03*
X1559387Y589340D03*
X1550487Y681565D03*
X1550320Y696562D03*
X1550917Y704332D03*
X1550390Y709885D03*
X1555937Y1042715D03*
X1563714Y572792D03*
X1564690Y663302D03*
X1562871Y735716D03*
X1567737Y1036815D03*
X1576740Y1080262D03*
X1579632Y787410D03*
X1579816Y793954D03*
X1588459Y1068895D03*
X1603530Y202402D03*
X1604240Y227892D03*
X1608307Y772125D03*
X1609239Y959331D03*
X1602650Y1242752D03*
X1608000Y1261662D03*
X1609403Y1247684D03*
X1623881Y117627D03*
X1623107Y769805D03*
X1616927Y952415D03*
X1623744Y996980D03*
X1620727Y1256225D03*
X1624600Y1262074D03*
X1619454Y1249290D03*
X1624040Y1247202D03*
X1623930Y1252242D03*
X1614116Y1411169D03*
X1636393Y181778D03*
X1633111Y206693D03*
X1642135Y414202D03*
X1638713Y722692D03*
X1639689Y1259345D03*
X1639467Y1250175D03*
X1630643Y1440290D03*
X1636200Y1436862D03*
X1647110Y434177D03*
X1654110D03*
X1658275Y527195D03*
X1649291Y556057D03*
X1645530Y549160D03*
X1645300Y612202D03*
X1653319Y642311D03*
X1648722Y645613D03*
Y679613D03*
X1649455Y711844D03*
X1652807Y769805D03*
X1646627Y952415D03*
Y959265D03*
X1651404Y992838D03*
X1648368Y1245574D03*
X1644714Y1249914D03*
X1649573Y1252942D03*
X1654600Y1262742D03*
X1668100Y180852D03*
X1666690Y193290D03*
X1674432Y216981D03*
X1668426Y222432D03*
X1660861Y227548D03*
X1661110Y434177D03*
X1667376Y515531D03*
X1665790Y523417D03*
X1666840Y544332D03*
X1662467Y530301D03*
X1668917Y549992D03*
X1663502Y555115D03*
X1660660Y602273D03*
X1669489Y1259545D03*
X1661300Y1252085D03*
X1669731Y1248688D03*
X1664867Y1303505D03*
X1671870Y1438296D03*
X1665940Y1512862D03*
X1666123Y1524862D03*
Y1537862D03*
Y1553557D03*
X1666198Y1565557D03*
X1671660Y1569412D03*
X1666198Y1585321D03*
X1690208Y421855D03*
X1689121Y488288D03*
X1681817Y495290D03*
X1686564Y497580D03*
X1675664Y513802D03*
X1690999Y513107D03*
X1683702Y514687D03*
X1676600Y523902D03*
X1687166Y529824D03*
X1684810Y523602D03*
X1688768Y518107D03*
X1685766Y535011D03*
X1685358Y539743D03*
X1679941Y552222D03*
X1678860Y556752D03*
X1683369Y562698D03*
X1683087Y712055D03*
X1686041Y763095D03*
X1676427Y952415D03*
Y959265D03*
X1675642Y989103D03*
X1682942Y1258909D03*
X1679522Y1249489D03*
X1683578Y1253780D03*
X1683500Y1264312D03*
X1678067Y1303505D03*
X1680720Y1487062D03*
X1678340Y1500862D03*
X1677930Y1520362D03*
X1678340Y1541362D03*
X1678230Y1590542D03*
X1703026Y188993D03*
X1699740Y207090D03*
X1693987Y230174D03*
X1703487Y232174D03*
X1698220Y369652D03*
X1702959Y404243D03*
X1707780Y410738D03*
X1697161Y406602D03*
X1692429Y403985D03*
X1701124Y423802D03*
X1694050Y416643D03*
X1695455Y422287D03*
X1707544Y431745D03*
X1707568Y420370D03*
X1697648Y463724D03*
X1693720Y455862D03*
X1702127Y468719D03*
X1697210Y500802D03*
X1694158Y504875D03*
X1707200Y498962D03*
X1699553Y513107D03*
X1707552Y506731D03*
X1707716Y513562D03*
X1702930Y526102D03*
X1701726Y518107D03*
X1699107Y555783D03*
X1703306Y550064D03*
X1692883Y703943D03*
X1701320Y705678D03*
X1693087Y712055D03*
X1696402Y709533D03*
X1706027Y952415D03*
Y959265D03*
X1705242Y989103D03*
X1696061Y1014019D03*
X1705076Y1242032D03*
X1699089Y1258842D03*
X1699431Y1248688D03*
X1699030Y1263912D03*
X1702817Y1374325D03*
X1702417Y1364595D03*
X1691988Y1517803D03*
Y1538803D03*
Y1558262D03*
X1705723Y1583821D03*
X1715210Y18282D03*
X1709589Y26062D03*
X1720895Y68062D03*
X1709000Y87362D03*
X1712720Y111862D03*
X1714180Y154790D03*
X1711599Y197329D03*
X1721220Y458362D03*
X1713977Y457137D03*
X1708977Y458542D03*
X1713158Y478243D03*
X1718786Y467517D03*
X1713977Y470804D03*
X1708977D03*
X1711720Y497964D03*
X1709356Y541144D03*
X1716480Y691410D03*
X1714897Y706095D03*
X1709828Y719283D03*
X1712207Y769805D03*
X1719277Y1013205D03*
X1710363Y1249132D03*
X1713930Y1262074D03*
X1718149Y1496270D03*
X1717149Y1505895D03*
X1717988Y1520951D03*
X1711988D03*
X1717149Y1513945D03*
X1717988Y1530445D03*
X1711988D03*
X1729080Y118132D03*
X1739720Y120892D03*
X1728999Y112895D03*
X1733920Y151362D03*
X1728320Y169862D03*
X1737470Y177147D03*
X1725344Y359334D03*
X1729810Y390620D03*
X1737660D03*
X1734290Y423820D03*
X1739316Y480939D03*
X1728139Y952481D03*
Y959331D03*
X1728924Y987935D03*
X1728477Y1242955D03*
X1728689Y1258845D03*
X1739237Y1256935D03*
X1736715Y1249405D03*
X1727674Y1513945D03*
X1729310Y1520951D03*
X1735310D03*
X1729310Y1530445D03*
X1735310D03*
X1726988Y1554631D03*
Y1547131D03*
X1748720Y97362D03*
X1745010Y122952D03*
X1750820Y119972D03*
X1747591Y171733D03*
X1751068Y262123D03*
X1754245Y269724D03*
X1746484Y279682D03*
X1756204Y301695D03*
X1756933Y372452D03*
X1744380Y382892D03*
X1744510Y377452D03*
X1747080Y435870D03*
X1746720Y464862D03*
X1740886Y493960D03*
X1743440Y721802D03*
X1745541Y763095D03*
X1743710Y1262074D03*
X1742337Y1252300D03*
X1747677Y1507388D03*
X1747304Y1524976D03*
X1741988Y1554631D03*
Y1547131D03*
X1768026Y24165D03*
X1769669Y15244D03*
X1761998Y15187D03*
X1765260Y18262D03*
X1757320Y15872D03*
X1767185Y48817D03*
X1771774Y53682D03*
X1767170Y83607D03*
X1767990Y76797D03*
X1760478Y90027D03*
X1768483Y166260D03*
X1765820Y182282D03*
X1767300Y174587D03*
X1760104Y301648D03*
X1770520Y364148D03*
X1765670Y458012D03*
X1767300Y465893D03*
X1768317Y686375D03*
X1770017Y701175D03*
Y721175D03*
Y711175D03*
X1757839Y952481D03*
Y959331D03*
X1764742Y989103D03*
X1758189Y1258875D03*
X1769037Y1256835D03*
X1759070Y1249412D03*
X1770299Y1249182D03*
X1764163Y1246974D03*
X1758352Y1317368D03*
Y1322168D03*
X1771988Y1554631D03*
Y1547131D03*
X1756988Y1554631D03*
Y1547131D03*
X1775556Y21471D03*
X1775830Y26522D03*
X1779411Y50692D03*
X1774328Y62987D03*
X1775580Y73330D03*
X1787790Y85132D03*
X1781485Y88192D03*
X1785142Y76032D03*
X1773611Y88293D03*
X1780320Y153162D03*
X1774950Y167392D03*
X1779500Y171692D03*
X1782600Y175932D03*
X1777354Y295489D03*
X1782420Y443987D03*
X1773870Y438222D03*
X1781720Y592742D03*
X1773559Y763642D03*
X1787539Y952481D03*
Y959331D03*
X1788219Y1259312D03*
X1773390Y1262074D03*
X1788531Y1248688D03*
X1773480Y1253692D03*
X1788360Y1264522D03*
X1784680Y1553922D03*
X1786988Y1547131D03*
X1797324Y161465D03*
X1799250Y297932D03*
X1803129Y362293D03*
X1802929Y385293D03*
X1792450Y410615D03*
X1792507Y403932D03*
X1792220Y425432D03*
X1792335Y418775D03*
X1804841Y763095D03*
X1794442Y989103D03*
X1802670Y1239522D03*
X1803100Y1262074D03*
X1803357Y1251204D03*
X1795484Y1496401D03*
X1800450Y1505230D03*
X1792645Y1511423D03*
X1795561Y1524729D03*
X1806920Y150862D03*
X1808910Y143902D03*
X1813335Y155435D03*
X1810835Y163986D03*
X1819939Y177243D03*
X1813325Y177257D03*
X1813740Y281712D03*
X1820307Y373829D03*
X1820144Y398052D03*
X1819374Y410432D03*
X1818874Y423932D03*
X1810792Y417432D03*
X1818816Y468872D03*
X1818290Y1232452D03*
X1815474Y1246472D03*
X1814537Y1322105D03*
X1807150Y1505675D03*
X1818004Y1510021D03*
X1818410Y1525815D03*
X1828204Y328654D03*
X1829189Y363731D03*
X1824827Y952415D03*
Y959265D03*
X1824042Y989103D03*
X1829920Y1258322D03*
X1829940Y1263662D03*
X1828510Y1525915D03*
X1841257Y151402D03*
X1838910Y185772D03*
X1844157Y182210D03*
G54D20*
X40839Y772416D03*
X74169Y384676D03*
X77121Y696065D03*
X80971D03*
X90396Y695397D03*
X109200Y640346D03*
X105400Y642546D03*
X99516Y693707D03*
X99779Y761928D03*
X103779D03*
X107779D03*
X95779D03*
X112497Y516748D03*
X112900Y640946D03*
X126092Y641627D03*
X136029Y761028D03*
X140029D03*
X140104Y1557561D03*
X144029Y761028D03*
X148029D03*
X144120Y1358796D03*
X153789Y1397410D03*
X155100Y1720566D03*
X168562Y397487D03*
X191602Y762349D03*
X187602D03*
X183602D03*
X182727Y1358685D03*
X190332Y1397385D03*
X190971Y1410654D03*
X205320Y676846D03*
X207602Y762349D03*
X203602D03*
X195602D03*
X199602D03*
X209220Y676846D03*
X211602Y762349D03*
X214580Y1358678D03*
X238063Y34237D03*
X248442Y772391D03*
X257342Y771691D03*
X245066Y1257365D03*
X269046Y732948D03*
Y723153D03*
X265043D03*
X273000Y743488D03*
X268870Y747052D03*
X286046Y723153D03*
X282120Y723051D03*
X288646Y752348D03*
X295520Y18221D03*
X298720Y45846D03*
X290720D03*
X301038Y716669D03*
X294687Y707554D03*
X297087Y726901D03*
X301038Y723808D03*
X304602Y733478D03*
X296706Y752292D03*
X300839Y1318675D03*
X306207Y1355531D03*
X302401Y1363020D03*
X306720Y45846D03*
X320656Y726272D03*
X316656D03*
X317967Y743818D03*
X338161Y718274D03*
X328656Y726272D03*
X335126Y733782D03*
X327096Y741782D03*
X336446Y752292D03*
X328620Y1308036D03*
X338300Y1332733D03*
X336179Y1340002D03*
X340446Y752292D03*
X344446D03*
X370902D03*
X362902D03*
X358902D03*
X368391Y1325415D03*
X382902Y752292D03*
X378902D03*
X386902D03*
X372428Y1319407D03*
X383740Y1663466D03*
X390820Y1281346D03*
X400462Y1325076D03*
X405156Y1319772D03*
X416127Y1411149D03*
X431728Y1325051D03*
X424320Y1405046D03*
X430910Y1405056D03*
X432851Y1621321D03*
X436701Y1319213D03*
X450294Y1420453D03*
X440270Y1622256D03*
X444600Y1622416D03*
X460800Y383046D03*
X468831Y1280975D03*
X468790Y1319175D03*
X464191Y1325076D03*
X473013Y1033108D03*
X499510Y84106D03*
X490963Y1280928D03*
X496319Y1338502D03*
X501013Y1332582D03*
X488570Y1416305D03*
X503150Y74456D03*
X507310Y74476D03*
X529720Y38346D03*
X525900Y114184D03*
X530052Y1315590D03*
X533423Y1355531D03*
X528929Y1361575D03*
X539720Y38346D03*
X534720D03*
X542530Y120216D03*
X546370D03*
X554720Y38346D03*
X572500D03*
X568500D03*
X590100Y59846D03*
X597220Y91346D03*
X592220D03*
X595597Y750914D03*
X608250Y752949D03*
X611760Y746954D03*
X599763Y750930D03*
X614750Y760449D03*
Y767449D03*
X608225Y760514D03*
X607340Y886581D03*
X631130Y58766D03*
X624831Y166116D03*
X629002Y166071D03*
X639000Y63346D03*
X635000D03*
X633673Y1256232D03*
X649047Y36594D03*
X664342Y777591D03*
X661942Y1404719D03*
X671942Y773191D03*
X667408Y1397435D03*
X685968Y55666D03*
X690220D03*
X686588Y90321D03*
X696760Y131216D03*
X688247Y384639D03*
X692247D03*
X694720Y489471D03*
X690720D03*
X693310Y760145D03*
X688967Y790476D03*
X696860Y1358964D03*
X707500Y78346D03*
X708110Y85596D03*
X703500Y78346D03*
X712100Y85596D03*
X701362Y760145D03*
X697336D03*
X705388D03*
X710688D03*
X701830Y1404679D03*
X703951Y1397410D03*
X708219Y1637835D03*
X724644Y55029D03*
X729293D03*
X719949D03*
X723400Y85546D03*
X728909Y763688D03*
X714688Y760145D03*
X718688D03*
X728199Y1358703D03*
X724452Y1587002D03*
X724392Y1607247D03*
X716202Y1607230D03*
X737595Y55029D03*
X741377D03*
X733642D03*
X745474D03*
X732501Y77932D03*
X736601D03*
X745220Y514346D03*
X736909Y763688D03*
X745009Y763748D03*
X732909Y763688D03*
X740909D03*
X749477Y55029D03*
X751220Y514346D03*
X753009Y763748D03*
X749009D03*
X757009D03*
X758758Y1669425D03*
X765188Y1588185D03*
X768714Y1669425D03*
X808797Y436409D03*
X808297Y1591267D03*
X833445Y226202D03*
X849767Y1242960D03*
X850415Y1590731D03*
X898087Y465896D03*
X902875D03*
X907420Y469046D03*
X905010Y493771D03*
X892332Y1591127D03*
X911520Y469046D03*
X916111Y512011D03*
X921149Y523040D03*
X919350Y982516D03*
X919300Y993136D03*
X914500Y1666884D03*
X937643Y514834D03*
X926380Y982666D03*
X961445Y384238D03*
X972379Y506775D03*
X960620Y506746D03*
X980092Y415880D03*
X992345D03*
X994956Y427386D03*
X1020069Y302897D03*
X1009000Y383346D03*
X1024099Y302897D03*
X1035688Y393021D03*
X1047500Y387346D03*
X1053749Y763308D03*
X1057749D03*
X1065749D03*
X1061749D03*
X1087196Y763963D03*
X1083296D03*
X1091096D03*
X1098896D03*
X1102796D03*
X1094996D03*
X1115869Y764048D03*
X1106696Y763963D03*
X1119869Y764048D03*
X1110680Y764125D03*
X1105717Y1257865D03*
X1117420Y1395297D03*
X1127869Y764048D03*
X1123869D03*
X1127100Y1433739D03*
X1121753Y1441063D03*
X1126100Y1447766D03*
X1149467Y592006D03*
X1145467D03*
X1142921Y1257661D03*
X1151687Y1580222D03*
X1141687D03*
X1145687D03*
X1153537Y605996D03*
X1153477Y599026D03*
X1163891Y1258088D03*
X1156552Y1395269D03*
X1163643Y1433714D03*
X1164172Y1447013D03*
X1161095Y1580222D03*
X1155687D03*
X1165095D03*
X1172742Y773891D03*
X1179842Y781791D03*
X1171095Y1580222D03*
X1175095D03*
X1197396Y598805D03*
Y605820D03*
X1187891Y1395008D03*
X1228704Y109046D03*
X1228860Y764249D03*
X1222707Y763409D03*
X1249122Y755891D03*
X1242260Y763449D03*
X1235360D03*
X1258195Y129321D03*
X1260544Y231006D03*
X1256193Y733649D03*
X1252847Y741279D03*
X1263937Y745449D03*
X1266723Y106644D03*
X1280291Y245598D03*
X1277257Y736469D03*
X1273257Y736549D03*
X1280797Y743449D03*
X1274198Y750575D03*
X1276980Y1314736D03*
X1282313Y1355531D03*
X1280192Y1362800D03*
X1297821Y103072D03*
X1283485Y115039D03*
X1287641D03*
X1291704Y115078D03*
X1284120Y244626D03*
X1295947Y728209D03*
X1292007Y730219D03*
X1294937Y752449D03*
X1284797Y745169D03*
X1299890Y130226D03*
X1313597Y745279D03*
X1301487Y752779D03*
X1303761Y1316036D03*
X1314441Y1332733D03*
X1312320Y1340002D03*
X1328020Y179205D03*
X1322501Y186083D03*
X1317567Y745289D03*
X1330888Y752493D03*
X1346604Y149416D03*
X1342525D03*
X1343012Y206527D03*
X1334298Y741636D03*
X1344532Y1325415D03*
X1353850Y140156D03*
X1348241Y207005D03*
X1348569Y1319407D03*
X1367420Y1281546D03*
X1381297Y1319772D03*
X1406963Y1405029D03*
X1412842Y1319213D03*
X1426435Y1420453D03*
X1444852Y1281445D03*
X1444931Y1319175D03*
X1449443Y1032797D03*
X1455734Y1398879D03*
X1469067Y734339D03*
X1466984Y1281398D03*
X1477154Y1332582D03*
X1472460Y1338502D03*
X1465747Y1416849D03*
X1478656Y752285D03*
X1490992Y752648D03*
X1486741Y752286D03*
X1503645Y752749D03*
X1509564Y1355531D03*
X1505070Y1361575D03*
X1517575Y744414D03*
X1584000Y752846D03*
X1582000Y759846D03*
X1590915Y761529D03*
X1582017Y903549D03*
X1602788Y761679D03*
X1594997Y761499D03*
X1606788Y761679D03*
X1618788D03*
X1610788D03*
X1614788D03*
X1622077Y1440000D03*
X1638928Y761679D03*
X1630928D03*
X1634928D03*
X1628600Y1431111D03*
X1653220Y618146D03*
X1654667Y762718D03*
X1662276Y543445D03*
X1658679Y762718D03*
X1666686D03*
X1662656D03*
X1658026Y1391710D03*
X1665117Y1431006D03*
X1665666Y1444265D03*
X1685686Y482137D03*
X1703000Y96346D03*
X1699000D03*
X1699150Y508536D03*
X1702848Y763552D03*
X1689565Y1391449D03*
X1710025Y21376D03*
X1713173Y34228D03*
X1708000Y96346D03*
X1708680Y175234D03*
X1707160Y207184D03*
X1710057Y698949D03*
X1709486Y713971D03*
X1714955Y763560D03*
X1710915D03*
X1706948Y763552D03*
X1769791Y34338D03*
X1758075Y43193D03*
X1755378Y231012D03*
X1779575Y16706D03*
X1774435Y16726D03*
G54D11*
X32370Y147842D03*
X46480Y1574922D03*
X928900Y1185132D03*
X1726300Y1710102D03*
X1796240Y126972D03*
G54D21*
X33583Y1256964D03*
Y1252965D03*
X48742Y393408D03*
X48575Y386993D03*
X49583Y1256964D03*
X65412Y443677D03*
X71374Y763164D03*
X63283Y1256964D03*
X87762Y659641D03*
Y663141D03*
X90024Y667952D03*
X91992Y673881D03*
Y677881D03*
X88962Y725640D03*
X92983Y1256964D03*
X79283D03*
X107934Y505374D03*
Y509374D03*
Y517925D03*
X99427Y649839D03*
X99497Y642149D03*
X99467Y646009D03*
X108983Y1256964D03*
X120208Y501638D03*
X120238Y507877D03*
Y512983D03*
X127084Y646822D03*
X125092Y667700D03*
X122683Y1256964D03*
Y1250499D03*
X143724Y1257952D03*
X157102Y511095D03*
X146982Y522771D03*
X146332Y694970D03*
X146232Y703270D03*
X152383Y1256964D03*
X152746Y1546009D03*
X145140Y1598155D03*
Y1602666D03*
X168383Y1256964D03*
X182083D03*
X198083D03*
X211783D03*
X241351Y1257456D03*
X227583Y1257520D03*
X257351Y1255756D03*
Y1251564D03*
X261750Y958053D03*
X330709Y205049D03*
X396393Y1412991D03*
Y1416491D03*
X414031Y929165D03*
X419915Y1415275D03*
X406388Y1418492D03*
X408004Y1413662D03*
X435809Y1626419D03*
X451984Y341362D03*
X449454Y1427968D03*
X461484Y341362D03*
X453033Y1411678D03*
X480907Y1402364D03*
X478384Y1408172D03*
X570449Y114132D03*
X570389Y109622D03*
X588490Y747887D03*
X611845Y145473D03*
X612012Y151888D03*
X613122Y774712D03*
X608614Y891364D03*
Y895384D03*
X619734Y34652D03*
X626774Y61272D03*
X619704Y442862D03*
Y457862D03*
Y452862D03*
Y447862D03*
Y462862D03*
X634704Y421362D03*
X649704Y416362D03*
Y431362D03*
Y457862D03*
Y452862D03*
Y447862D03*
Y462862D03*
X656213Y973428D03*
X656547Y989241D03*
Y985321D03*
X656483Y1256964D03*
X669464Y202362D03*
Y206362D03*
Y210362D03*
X673869Y1255932D03*
X687166Y35057D03*
X686183Y1256964D03*
X702747Y412255D03*
X702509Y417500D03*
X702469Y421540D03*
X711204Y484862D03*
Y488862D03*
X707996Y1595623D03*
X708203Y1641851D03*
X718984Y82562D03*
X717531Y412269D03*
X715883Y1256964D03*
X713704Y1301162D03*
Y1297162D03*
X725736Y1593913D03*
X741204Y408362D03*
Y404362D03*
X731944Y411382D03*
X745735Y1257681D03*
X732016Y1249625D03*
X750504Y74562D03*
X757596Y1581783D03*
Y1577203D03*
X763704Y413212D03*
Y408212D03*
Y423212D03*
Y418212D03*
X762824Y469862D03*
Y464862D03*
X777792Y484802D03*
X777824Y488862D03*
X762829Y501662D03*
X762841Y497658D03*
X770171Y753179D03*
X775283Y1256964D03*
X763301Y1257572D03*
X778797Y432665D03*
X791491Y432555D03*
X802004Y139262D03*
Y144262D03*
X800874Y308062D03*
X804983Y1256964D03*
X813148Y276820D03*
X813202Y284311D03*
X834683Y1256964D03*
X852715Y301542D03*
X852874Y308852D03*
X863049Y269220D03*
X895465Y506875D03*
X906058Y507348D03*
X906564Y500117D03*
Y503631D03*
X912068Y493611D03*
X922384Y986242D03*
X931409Y197612D03*
X937852Y505977D03*
X937847Y501925D03*
X937878Y498083D03*
X969273Y386189D03*
X958181Y403656D03*
Y399401D03*
X969284Y402017D03*
X969340Y398138D03*
X960090Y1559276D03*
X960130Y1563256D03*
X1003484Y380862D03*
X994484Y387362D03*
Y383362D03*
Y391362D03*
X994565Y400607D03*
X1004730Y422682D03*
X1015814Y194609D03*
X1018747Y420548D03*
X1009719Y1257810D03*
Y1253869D03*
X1022644Y194609D03*
X1025725Y1256944D03*
X1031939Y1251503D03*
X1039425Y1256944D03*
X1069125D03*
Y1251277D03*
X1098825Y1256944D03*
X1095456Y1251409D03*
X1119891Y1253449D03*
X1128525Y1256944D03*
X1134945Y1251483D03*
X1158225Y1256944D03*
X1174484Y1020362D03*
X1191642Y220362D03*
X1196257Y588714D03*
X1187925Y1256944D03*
X1204371Y599133D03*
X1204731Y605605D03*
X1230577Y116962D03*
X1231577Y134262D03*
X1220217Y126942D03*
X1220184Y134600D03*
X1220214Y130810D03*
X1232107Y156672D03*
X1233494Y192482D03*
X1242204Y193362D03*
X1242077Y217462D03*
X1242104Y221562D03*
X1253069Y120107D03*
X1253070Y124107D03*
X1255637Y752449D03*
X1272848Y196622D03*
X1273077Y229462D03*
Y225462D03*
X1316191Y731375D03*
X1326267Y737747D03*
X1345075Y120618D03*
X1337093Y179062D03*
Y183068D03*
X1343570Y195530D03*
X1337219Y187059D03*
X1337181Y191009D03*
X1343521Y199534D03*
X1342118Y212239D03*
X1333784Y204900D03*
X1359046Y128285D03*
X1352076Y124718D03*
X1365646Y124123D03*
Y128285D03*
X1373450Y1402334D03*
X1372534Y1416491D03*
Y1412791D03*
X1390371Y928806D03*
X1396056Y1415275D03*
X1384429Y1413792D03*
Y1417304D03*
X1425465Y1427948D03*
X1429584Y721944D03*
X1429581Y717865D03*
X1434744Y732212D03*
X1429160Y1412108D03*
X1456204Y149362D03*
Y153362D03*
Y161862D03*
Y165862D03*
Y157862D03*
Y173862D03*
Y177862D03*
Y181862D03*
Y169862D03*
X1454457Y1408139D03*
X1467704Y145362D03*
X1463191Y746305D03*
X1484533Y309257D03*
X1592082Y215568D03*
X1592062Y207567D03*
X1592046Y235982D03*
X1607404Y725062D03*
X1613004Y583362D03*
X1632625Y1256944D03*
X1643203Y647963D03*
X1649282Y653741D03*
X1643203Y681963D03*
X1649282Y687742D03*
X1649400Y721761D03*
X1643203Y715963D03*
X1648710Y1257492D03*
X1670017Y539680D03*
X1669531Y534524D03*
X1657713Y536071D03*
Y532071D03*
X1669987Y528335D03*
X1657713Y544622D03*
X1662325Y1256944D03*
X1682162Y479078D03*
Y482590D03*
X1697654Y198330D03*
X1697634Y202470D03*
X1696706Y475583D03*
X1696670Y486806D03*
X1697444Y481422D03*
X1696760Y537507D03*
X1692025Y1256944D03*
X1716247Y39654D03*
Y43654D03*
Y47654D03*
Y51654D03*
X1707054Y199720D03*
X1721725Y1256944D03*
X1751425D03*
X1761096Y716448D03*
X1761196Y724648D03*
X1781125Y1256944D03*
X1796773Y1253019D03*
Y1256819D03*
X1812806Y1510437D03*
G54D12*
X45775Y393408D03*
X45608Y386993D03*
X30616Y1256964D03*
Y1252965D03*
X62445Y443677D03*
X60316Y1256964D03*
X46616D03*
X68407Y763164D03*
X76316Y1256964D03*
X84795Y659641D03*
Y663141D03*
X87057Y667952D03*
X89025Y673881D03*
Y677881D03*
X85995Y725640D03*
X90016Y1256964D03*
X104967Y505374D03*
Y509374D03*
Y517925D03*
X96460Y649839D03*
X96530Y642149D03*
X96500Y646009D03*
X106016Y1256964D03*
X117241Y501638D03*
X117271Y507877D03*
Y512983D03*
X124117Y646822D03*
X122125Y667700D03*
X119716Y1256964D03*
Y1250499D03*
X143365Y694970D03*
X143265Y703270D03*
X140757Y1257952D03*
X142173Y1598155D03*
Y1602666D03*
X154135Y511095D03*
X144015Y522771D03*
X149416Y1256964D03*
X149779Y1546009D03*
X165416Y1256964D03*
X179116D03*
X208816D03*
X195116D03*
X224616Y1257520D03*
X238384Y1257456D03*
X254384Y1255756D03*
Y1251564D03*
X258783Y958053D03*
X327742Y205049D03*
X403421Y1418492D03*
X393426Y1412991D03*
Y1416491D03*
X411064Y929165D03*
X416948Y1415275D03*
X405037Y1413662D03*
X432842Y1626419D03*
X449017Y341362D03*
X450066Y1411678D03*
X446487Y1427968D03*
X458517Y341362D03*
X477940Y1402364D03*
X475417Y1408172D03*
X567482Y114132D03*
X567422Y109622D03*
X585523Y747887D03*
X608878Y145473D03*
X609045Y151888D03*
X610155Y774712D03*
X605647Y891364D03*
Y895384D03*
X616767Y34652D03*
X623807Y61272D03*
X631737Y421362D03*
X616737Y442862D03*
Y457862D03*
Y452862D03*
Y447862D03*
Y462862D03*
X646737Y416362D03*
Y431362D03*
Y457862D03*
Y452862D03*
Y447862D03*
Y462862D03*
X653246Y973428D03*
X653580Y989241D03*
Y985321D03*
X653516Y1256964D03*
X666497Y202362D03*
Y206362D03*
Y210362D03*
X670902Y1255932D03*
X684199Y35057D03*
X683216Y1256964D03*
X699780Y412255D03*
X699542Y417500D03*
X699502Y421540D03*
X708237Y484862D03*
Y488862D03*
X712916Y1256964D03*
X710737Y1301162D03*
Y1297162D03*
X705029Y1595623D03*
X705236Y1641851D03*
X716017Y82562D03*
X714564Y412269D03*
X728977Y411382D03*
X729049Y1249625D03*
X722769Y1593913D03*
X738237Y408362D03*
Y404362D03*
X742768Y1257681D03*
X747537Y74562D03*
X760737Y413212D03*
Y408212D03*
Y423212D03*
Y418212D03*
X759857Y469862D03*
Y464862D03*
X759862Y501662D03*
X759874Y497658D03*
X760334Y1257572D03*
X754629Y1581783D03*
Y1577203D03*
X775830Y432665D03*
X774825Y484802D03*
X774857Y488862D03*
X767204Y753179D03*
X772316Y1256964D03*
X788524Y432555D03*
X799037Y139262D03*
Y144262D03*
X810181Y276820D03*
X810235Y284311D03*
X797907Y308062D03*
X802016Y1256964D03*
X831716D03*
X849748Y301542D03*
X849907Y308852D03*
X860082Y269220D03*
X892498Y506875D03*
X903091Y507348D03*
X903597Y500117D03*
Y503631D03*
X909101Y493611D03*
X919417Y986242D03*
X928442Y197612D03*
X934885Y505977D03*
X934880Y501925D03*
X934911Y498083D03*
X955214Y403656D03*
Y399401D03*
X957123Y1559276D03*
X957163Y1563256D03*
X966306Y386189D03*
X966317Y402017D03*
X966373Y398138D03*
X1000517Y380862D03*
X991517Y387362D03*
Y383362D03*
Y391362D03*
X991598Y400607D03*
X1001763Y422682D03*
X1019677Y194609D03*
X1012847D03*
X1015780Y420548D03*
X1006752Y1257810D03*
Y1253869D03*
X1036458Y1256944D03*
X1022758D03*
X1028972Y1251503D03*
X1066158Y1256944D03*
Y1251277D03*
X1095858Y1256944D03*
X1092489Y1251409D03*
X1116924Y1253449D03*
X1125558Y1256944D03*
X1131978Y1251483D03*
X1155258Y1256944D03*
X1171517Y1020362D03*
X1184958Y1256944D03*
X1188675Y220362D03*
X1193290Y588714D03*
X1217250Y126942D03*
X1217217Y134600D03*
X1217247Y130810D03*
X1201404Y599133D03*
X1201764Y605605D03*
X1227610Y116962D03*
X1228610Y134262D03*
X1229140Y156672D03*
X1230527Y192482D03*
X1239237Y193362D03*
X1239110Y217462D03*
X1239137Y221562D03*
X1250102Y120107D03*
X1250103Y124107D03*
X1252670Y752449D03*
X1269881Y196622D03*
X1270110Y229462D03*
Y225462D03*
X1313224Y731375D03*
X1330817Y204900D03*
X1323300Y737747D03*
X1342108Y120618D03*
X1334126Y179062D03*
Y183068D03*
X1340603Y195530D03*
X1334252Y187059D03*
X1334214Y191009D03*
X1340554Y199534D03*
X1339151Y212239D03*
X1362679Y124123D03*
Y128285D03*
X1356079D03*
X1349109Y124718D03*
X1370483Y1402334D03*
X1369567Y1416491D03*
Y1412791D03*
X1387404Y928806D03*
X1393089Y1415275D03*
X1381462Y1413792D03*
Y1417304D03*
X1426617Y721944D03*
X1426614Y717865D03*
X1426193Y1412108D03*
X1422498Y1427948D03*
X1431777Y732212D03*
X1453237Y149362D03*
Y153362D03*
Y161862D03*
Y165862D03*
Y157862D03*
Y173862D03*
Y177862D03*
Y181862D03*
Y169862D03*
X1460224Y746305D03*
X1451490Y1408139D03*
X1464737Y145362D03*
X1481566Y309257D03*
X1589115Y215568D03*
X1589095Y207567D03*
X1589079Y235982D03*
X1604437Y725062D03*
X1610037Y583362D03*
X1640236Y647963D03*
Y681963D03*
Y715963D03*
X1629658Y1256944D03*
X1654746Y536071D03*
Y532071D03*
Y544622D03*
X1646315Y653741D03*
Y687742D03*
X1646433Y721761D03*
X1645743Y1257492D03*
X1667050Y539680D03*
X1666564Y534524D03*
X1667020Y528335D03*
X1659358Y1256944D03*
X1679195Y479078D03*
Y482590D03*
X1689058Y1256944D03*
X1704087Y199720D03*
X1694687Y198330D03*
X1694667Y202470D03*
X1693739Y475583D03*
X1693703Y486806D03*
X1694477Y481422D03*
X1693793Y537507D03*
X1713280Y39654D03*
Y43654D03*
Y47654D03*
Y51654D03*
X1718758Y1256944D03*
X1748458D03*
X1758129Y716448D03*
X1758229Y724648D03*
X1778158Y1256944D03*
X1793806Y1253019D03*
Y1256819D03*
X1809839Y1510437D03*
G54D30*
X159474Y1320753D03*
X183847Y1320778D03*
X208247D03*
X275289Y575702D03*
Y599861D03*
Y624015D03*
Y648169D03*
X278126Y676260D03*
Y700414D03*
X395771Y1242785D03*
X420171D03*
X444493D03*
X468893D03*
X493293D03*
X673093Y1320778D03*
X697466Y1320803D03*
X721866D03*
X1100800Y251488D03*
X1100700Y275788D03*
X1131100Y1357088D03*
X1155500D03*
X1179900D03*
X1371912Y1242785D03*
X1396312D03*
X1420634D03*
X1445034D03*
X1469434D03*
X1577000Y591888D03*
Y616388D03*
Y640888D03*
Y665288D03*
Y689788D03*
Y714288D03*
X1634259Y1354374D03*
X1658632Y1354399D03*
X1683032D03*
G54D22*
X32099Y1269464D03*
Y1262464D03*
X48099Y1269464D03*
Y1262464D03*
X61799Y1269464D03*
Y1262464D03*
X77799Y1269464D03*
Y1262464D03*
X91499Y1269464D03*
Y1262464D03*
X86520Y1531262D03*
Y1538262D03*
X107499Y1269464D03*
Y1262464D03*
X121199Y1269464D03*
Y1262464D03*
X137199Y1269464D03*
Y1262464D03*
X133914Y1562234D03*
Y1555234D03*
X150899Y1269464D03*
Y1262464D03*
X149669Y1354514D03*
Y1361514D03*
X166899Y1269464D03*
Y1262464D03*
X177239Y1354514D03*
Y1361514D03*
X168058Y1388498D03*
X176464D03*
X168058Y1395498D03*
X176464D03*
X180599Y1269464D03*
Y1262464D03*
X188215Y1354514D03*
Y1361514D03*
X210299Y1269464D03*
Y1262464D03*
X196599Y1269464D03*
Y1262464D03*
X206201Y1388498D03*
Y1395498D03*
X226448Y1011928D03*
Y1018928D03*
X226299Y1269464D03*
Y1262464D03*
X219980Y1353391D03*
Y1360391D03*
X214607Y1388498D03*
Y1395498D03*
X240072Y983774D03*
Y990774D03*
X239658Y1014086D03*
Y1021086D03*
X239999Y1269464D03*
Y1262464D03*
X256172Y983874D03*
Y990874D03*
X255528Y1014109D03*
X248102Y1014079D03*
X255528Y1021109D03*
X248102Y1021079D03*
X255999Y1269464D03*
Y1262464D03*
X321581Y1308970D03*
Y1301970D03*
X314318Y1308998D03*
Y1301998D03*
X322041Y1346644D03*
Y1353644D03*
X323544Y1368887D03*
Y1361887D03*
X335988Y1289012D03*
Y1296012D03*
X330447Y1346644D03*
Y1353644D03*
X354169Y1323846D03*
X355672Y1339089D03*
X354169Y1330846D03*
X355672Y1346089D03*
X363518Y1289012D03*
Y1296012D03*
X362575Y1323846D03*
Y1330846D03*
X376437Y1275059D03*
X384837D03*
X376437Y1282059D03*
X384837D03*
X387800Y1325663D03*
X386033Y1310043D03*
Y1317043D03*
X387800Y1332663D03*
X397518Y1275059D03*
Y1282059D03*
X394469Y1310043D03*
Y1317043D03*
X409367Y946135D03*
X416247Y946085D03*
X409061Y967360D03*
Y960360D03*
X416061Y967360D03*
Y960360D03*
X409367Y953135D03*
X416247Y953085D03*
X416061Y981840D03*
Y974840D03*
X409061Y981840D03*
Y974840D03*
Y996320D03*
Y989320D03*
X416061Y996320D03*
Y989320D03*
Y1010800D03*
Y1003800D03*
X409061D03*
Y1010800D03*
Y1025284D03*
Y1018284D03*
X416061Y1018280D03*
Y1025280D03*
X419928Y1325663D03*
X418425Y1310043D03*
Y1317043D03*
X419928Y1332663D03*
X423061Y933680D03*
Y946180D03*
Y940680D03*
Y967360D03*
Y960360D03*
Y953180D03*
Y981840D03*
Y974840D03*
Y996320D03*
Y989320D03*
Y1010800D03*
Y1003800D03*
Y1018280D03*
Y1025280D03*
X433274Y1275209D03*
X425274D03*
X433274Y1282209D03*
X425274D03*
X426831Y1310043D03*
Y1317043D03*
X450553Y1310420D03*
Y1317420D03*
X452056Y1325663D03*
Y1332663D03*
X458280Y932398D03*
X465107Y945885D03*
X458280Y945880D03*
Y939398D03*
X465280Y967360D03*
Y960360D03*
X458280Y967360D03*
Y960360D03*
X465107Y952885D03*
X458280Y952880D03*
Y981840D03*
Y974840D03*
X465280Y981840D03*
Y974840D03*
X458280Y996320D03*
Y989320D03*
X465280Y996320D03*
Y989320D03*
Y1010800D03*
Y1003800D03*
X458280Y1010800D03*
Y1003800D03*
X465280Y1018280D03*
Y1025280D03*
X458280Y1018280D03*
Y1025280D03*
X462713Y1275209D03*
Y1282209D03*
X458959Y1310420D03*
Y1317420D03*
X471917Y945805D03*
X472280Y967360D03*
Y960360D03*
X471917Y952805D03*
X472280Y981840D03*
Y974840D03*
Y996320D03*
Y989320D03*
Y1010800D03*
Y1003800D03*
Y1018280D03*
Y1025280D03*
X475821Y1275209D03*
X484221D03*
X475821Y1282209D03*
X484221D03*
X482681Y1310420D03*
Y1317420D03*
X483442Y1325423D03*
Y1332423D03*
X486773Y1440292D03*
Y1447292D03*
X496228Y1289012D03*
Y1296012D03*
X491087Y1310420D03*
Y1317420D03*
X495173Y1440292D03*
Y1447292D03*
X514809Y1323846D03*
X515199Y1339878D03*
X514809Y1330846D03*
X515199Y1346878D03*
X503573Y1440292D03*
Y1447292D03*
X523897Y1289012D03*
Y1296012D03*
X523215Y1323846D03*
Y1330846D03*
X537077Y1316970D03*
Y1309970D03*
X543907Y1316950D03*
Y1309950D03*
X546937Y1346644D03*
Y1353644D03*
X547327Y1369676D03*
Y1362676D03*
X555343Y1346644D03*
Y1353644D03*
X625355Y983045D03*
Y990045D03*
X625340Y1011835D03*
Y1018835D03*
X625299Y1269464D03*
Y1262464D03*
X641560Y981934D03*
Y988934D03*
X641044Y1013821D03*
X648527Y1013299D03*
Y1006299D03*
X633435Y1013821D03*
X641044Y1020821D03*
X633435D03*
X641299Y1269464D03*
Y1262464D03*
X654999Y1269464D03*
Y1262464D03*
X663288Y1354539D03*
Y1361539D03*
X670999Y1269464D03*
Y1262464D03*
X681677Y1388623D03*
Y1395623D03*
X684699Y1269464D03*
Y1262464D03*
X690826Y1354539D03*
Y1361539D03*
X690083Y1389123D03*
Y1396123D03*
X700699Y1269464D03*
Y1262464D03*
X714399Y1269464D03*
Y1262464D03*
X702239Y1354539D03*
Y1361539D03*
X730399Y1269464D03*
Y1262464D03*
X719820Y1388523D03*
X728226D03*
X719820Y1395523D03*
X728226D03*
X744099Y1269464D03*
Y1262464D03*
X733588Y1353416D03*
Y1360416D03*
X760099Y1269464D03*
Y1262464D03*
X773799Y1269464D03*
Y1262464D03*
X789799Y1269464D03*
Y1262464D03*
X803499Y1269464D03*
Y1262464D03*
X819499Y1269464D03*
Y1262464D03*
X833199Y1269464D03*
Y1262464D03*
X840246Y1269464D03*
Y1262464D03*
X968580Y211799D03*
Y204799D03*
X1015841Y1269344D03*
Y1262344D03*
X1024241Y1269444D03*
Y1262444D03*
X1037941Y1269444D03*
Y1262444D03*
X1053941Y1269444D03*
Y1262444D03*
X1067641Y1269444D03*
Y1262444D03*
X1083641Y1269444D03*
Y1262444D03*
X1097341Y1269444D03*
Y1262444D03*
X1113341Y1269444D03*
Y1262444D03*
X1127041Y1269444D03*
Y1262444D03*
X1122980Y1397844D03*
Y1390844D03*
X1143041Y1269444D03*
Y1262444D03*
X1150518Y1397844D03*
Y1390844D03*
X1149775Y1424827D03*
Y1431827D03*
X1141369Y1424827D03*
Y1431827D03*
X1156741Y1269444D03*
Y1262444D03*
X1161931Y1397844D03*
Y1390844D03*
X1186441Y1269444D03*
Y1262444D03*
X1172741Y1269444D03*
Y1262444D03*
X1179512Y1424827D03*
Y1431827D03*
X1202641Y1013744D03*
Y1020744D03*
X1202441Y1269444D03*
Y1262444D03*
X1193280Y1389721D03*
Y1396721D03*
X1187918Y1424827D03*
Y1431827D03*
X1216152Y983844D03*
Y990844D03*
X1215841Y1013744D03*
Y1020744D03*
X1216141Y1269444D03*
Y1262444D03*
X1232241Y983844D03*
Y990844D03*
X1232341Y1013744D03*
X1224241D03*
X1232341Y1020744D03*
X1224241D03*
X1232141Y1269444D03*
Y1262444D03*
X1263333Y267106D03*
Y260106D03*
X1270404Y267032D03*
Y260032D03*
X1289459Y1316998D03*
Y1309998D03*
X1296722Y1316970D03*
Y1309970D03*
X1298182Y1346644D03*
Y1353644D03*
X1299685Y1368887D03*
Y1361887D03*
X1312529Y1289012D03*
Y1296012D03*
X1306588Y1346644D03*
Y1353644D03*
X1330310Y1323846D03*
Y1330846D03*
X1331813Y1339089D03*
Y1346089D03*
X1340059Y1289012D03*
Y1296012D03*
X1338716Y1323846D03*
Y1330846D03*
X1352458Y1275529D03*
X1360858D03*
X1352458Y1282529D03*
X1360858D03*
X1362174Y1310043D03*
Y1317043D03*
X1363941Y1325496D03*
Y1332496D03*
X1379212Y210814D03*
Y217814D03*
X1373739Y1275529D03*
Y1282529D03*
X1370610Y1310043D03*
Y1317043D03*
X1386212Y210814D03*
Y217814D03*
X1392357Y945865D03*
X1385547Y946105D03*
X1392202Y967359D03*
Y960359D03*
X1392357Y952865D03*
X1385202Y967359D03*
Y960359D03*
X1385547Y953105D03*
X1392202Y981839D03*
Y974839D03*
X1385202Y981839D03*
Y974839D03*
X1392202Y996319D03*
Y989319D03*
X1385202Y996319D03*
Y989319D03*
X1392202Y1010799D03*
Y1003799D03*
X1385202D03*
Y1010799D03*
X1392202Y1018279D03*
Y1025279D03*
X1385202Y1025283D03*
Y1018283D03*
X1394566Y1310043D03*
Y1317043D03*
X1396069Y1325496D03*
Y1332496D03*
X1399202Y933379D03*
Y945879D03*
Y940379D03*
Y967359D03*
Y960359D03*
Y952879D03*
Y981839D03*
Y974839D03*
Y996319D03*
Y989319D03*
Y1010799D03*
Y1003799D03*
Y1018279D03*
Y1025279D03*
X1409295Y1275679D03*
X1401235D03*
X1409295Y1282679D03*
X1401235D03*
X1402972Y1310043D03*
Y1317043D03*
X1426694Y1310420D03*
Y1317420D03*
X1428197Y1325496D03*
Y1332496D03*
X1434421Y932397D03*
X1441287Y945975D03*
X1434421Y945879D03*
Y939397D03*
X1441421Y967359D03*
Y960359D03*
X1441287Y952975D03*
X1434421Y967359D03*
Y960359D03*
Y952879D03*
X1441421Y981839D03*
Y974839D03*
X1434421Y981839D03*
Y974839D03*
X1441421Y996319D03*
Y989319D03*
X1434421Y996319D03*
Y989319D03*
X1441421Y1010799D03*
Y1003799D03*
X1434421Y1010799D03*
Y1003799D03*
X1441421Y1018279D03*
Y1025279D03*
X1434421Y1018279D03*
Y1025279D03*
X1438734Y1275679D03*
Y1282679D03*
X1435100Y1310420D03*
Y1317420D03*
X1448127Y945775D03*
X1448421Y967359D03*
Y960359D03*
X1448127Y952775D03*
X1448421Y981839D03*
Y974839D03*
Y996319D03*
Y989319D03*
Y1010799D03*
Y1003799D03*
Y1018279D03*
Y1025279D03*
X1451842Y1275679D03*
X1460242D03*
X1451842Y1282679D03*
X1460242D03*
X1458822Y1310420D03*
Y1317420D03*
X1459583Y1325423D03*
Y1332423D03*
X1472449Y1289012D03*
Y1296012D03*
X1467228Y1310420D03*
Y1317420D03*
X1463294Y1440419D03*
Y1447419D03*
X1471694Y1440419D03*
Y1447419D03*
X1490950Y1323846D03*
Y1330846D03*
X1491340Y1339878D03*
Y1346878D03*
X1480094Y1440419D03*
Y1447419D03*
X1499912Y1290405D03*
Y1297405D03*
X1499247Y1323906D03*
Y1330906D03*
X1513718Y1308970D03*
Y1301970D03*
X1520528Y1309020D03*
Y1302020D03*
X1523078Y1346644D03*
Y1353644D03*
X1523468Y1368876D03*
Y1361876D03*
X1531456Y1346644D03*
Y1353644D03*
X1601397Y983725D03*
Y990725D03*
X1609477Y1013501D03*
X1601482Y1011815D03*
X1609477Y1020501D03*
X1601482Y1018815D03*
X1601441Y1269444D03*
Y1262444D03*
X1617526Y983867D03*
Y990867D03*
X1624206Y1013879D03*
Y1006879D03*
X1617386Y1013066D03*
Y1020066D03*
X1617441Y1269444D03*
Y1262444D03*
X1624454Y1387285D03*
Y1394285D03*
X1631141Y1269444D03*
Y1262444D03*
X1647141Y1269444D03*
Y1262444D03*
X1651992Y1387285D03*
Y1394285D03*
X1651249Y1422119D03*
X1642843D03*
X1651249Y1429119D03*
X1642843D03*
X1660841Y1269444D03*
Y1262444D03*
X1663405Y1387285D03*
Y1394285D03*
X1690541Y1269444D03*
Y1262444D03*
X1676841Y1269444D03*
Y1262444D03*
X1680986Y1422119D03*
X1689392D03*
X1680986Y1429119D03*
X1689392D03*
X1706541Y1269444D03*
Y1262444D03*
X1694954Y1386162D03*
Y1393162D03*
X1720241Y1269444D03*
Y1262444D03*
X1736241Y1269444D03*
Y1262444D03*
X1749941Y1269444D03*
Y1262444D03*
X1770898Y233128D03*
Y226128D03*
X1762878Y233128D03*
Y226128D03*
X1765941Y1269444D03*
Y1262444D03*
X1779378Y233128D03*
Y226128D03*
X1784810Y276992D03*
Y283992D03*
X1779641Y1269444D03*
Y1262444D03*
X1791850Y277002D03*
Y284002D03*
X1790320Y298032D03*
Y305032D03*
X1795641Y1269444D03*
Y1262444D03*
X1809341Y1269444D03*
Y1262444D03*
X1816714Y1269444D03*
Y1262444D03*
G54D31*
X159474Y1328627D03*
X183847Y1328652D03*
X208247D03*
X275289Y583576D03*
Y607735D03*
Y631889D03*
Y656043D03*
X270252Y676260D03*
Y700414D03*
X387897Y1242785D03*
X412297D03*
X436619D03*
X461019D03*
X485419D03*
X673093Y1328652D03*
X697466Y1328677D03*
X721866D03*
X1100800Y259362D03*
X1100700Y283662D03*
X1131100Y1364962D03*
X1155500D03*
X1179900D03*
X1364038Y1242785D03*
X1388438D03*
X1412760D03*
X1437160D03*
X1461560D03*
X1577000Y599762D03*
Y624262D03*
Y648762D03*
Y673162D03*
Y697662D03*
Y722162D03*
X1634259Y1362248D03*
X1658632Y1362273D03*
X1683032D03*
G54D40*
X338042Y849978D03*
X345178Y854584D03*
X348878Y880219D03*
X363679Y893036D03*
X375211Y1099017D03*
X393279Y893036D03*
X404378Y899445D03*
X406229Y915466D03*
X402529Y921875D03*
X400679Y944304D03*
X402529Y966735D03*
Y960326D03*
X401111Y1028523D03*
X406662Y1057361D03*
X402962Y1063770D03*
X401111Y1054157D03*
X409929Y896240D03*
X415478Y893036D03*
X422878D03*
X419178Y899445D03*
X422878Y912262D03*
X411779Y918670D03*
X415911Y1047749D03*
X408511D03*
X417762Y1057361D03*
X421462Y1050952D03*
X417762Y1063770D03*
Y1076587D03*
X412211Y1073383D03*
X417762Y1070178D03*
X412211Y1066974D03*
X419612Y1099017D03*
X414061Y1095813D03*
X430278Y893036D03*
X437678D03*
X426578Y899445D03*
X433978D03*
Y905853D03*
X426578D03*
X430279Y925079D03*
X432130Y934692D03*
X435830Y928283D03*
X427012Y1041340D03*
X432561Y1057361D03*
X428862Y1050952D03*
X423311Y1060565D03*
X428861Y1063770D03*
X432560Y1070178D03*
X425162D03*
X441378Y899445D03*
X445078Y893036D03*
X452479D03*
X448778Y899445D03*
X445079Y905853D03*
X452479D03*
X448780Y912262D03*
X441380D03*
X448779Y918670D03*
X454329Y915466D03*
X446930Y934692D03*
X443230Y928283D03*
X450630D03*
X439530Y934692D03*
X449211Y1054157D03*
X449213Y1060565D03*
X454762Y1050952D03*
Y1057361D03*
X451061Y1076587D03*
X451062Y1070178D03*
X459878Y893036D03*
X467278D03*
X456178Y899445D03*
X463578D03*
X470978D03*
X470980Y912262D03*
X470978Y918670D03*
X467278Y905853D03*
X461729Y909057D03*
X459878Y918670D03*
X465429Y921875D03*
X467711Y1047750D03*
X460311D03*
X471411Y1041340D03*
X456611D03*
X464011D03*
Y1054157D03*
X460311Y1060565D03*
X458460Y1070178D03*
X464011Y1066974D03*
X469560Y1070178D03*
X464011Y1073383D03*
X476529Y896240D03*
X478380Y912262D03*
X478379Y918670D03*
X478378Y905853D03*
X480228Y960326D03*
X482078Y982756D03*
X478379Y969939D03*
X475111Y1047749D03*
X478811Y1034931D03*
Y1066974D03*
X475111Y1073383D03*
X482511D03*
X530178Y893036D03*
X650599Y766798D03*
X667677Y441636D03*
X666741Y1255381D03*
X680928Y440061D03*
X671479Y443211D03*
X680928Y458959D03*
X677778Y468407D03*
X671479Y481006D03*
X667350Y470680D03*
X671479Y474707D03*
X684077Y433761D03*
X687227Y458959D03*
X696676Y471557D03*
X693526Y477856D03*
X731322Y421163D03*
X728172Y424313D03*
X731322Y440061D03*
X718723Y462108D03*
X726141Y1255381D03*
X737621Y424313D03*
X785541Y1255381D03*
X815241D03*
X1030780Y1266532D03*
X1088262Y1252293D03*
X1074480Y1263742D03*
X1133200Y1255702D03*
X1138783Y1255381D03*
X1168483D03*
X1181941Y766798D03*
X1224189Y1259155D03*
X1296999Y179649D03*
Y190749D03*
Y201849D03*
X1300393Y235762D03*
X1306617Y177799D03*
X1303407Y190749D03*
X1313025Y188899D03*
X1309833Y220349D03*
X1306627Y214799D03*
X1316242Y209249D03*
X1314184Y849978D03*
X1329062Y164849D03*
X1326918Y161161D03*
X1332268Y174099D03*
X1325857Y218499D03*
X1321320Y854584D03*
X1325020Y880219D03*
X1342903Y170399D03*
X1343521Y893036D03*
X1360186Y226264D03*
X1351354Y1099017D03*
X1373121Y893036D03*
X1380520Y899445D03*
X1378671Y921875D03*
Y966735D03*
Y960326D03*
X1377253Y1028523D03*
Y1047749D03*
X1377255Y1060565D03*
X1380953Y1054157D03*
X1377254Y1066974D03*
X1399020Y905853D03*
X1384220Y918670D03*
X1391621D03*
X1395753Y1047749D03*
X1384653D03*
X1390204Y1050952D03*
X1393904Y1057361D03*
X1382804Y1063770D03*
X1393904D03*
Y1076587D03*
X1388353Y1073383D03*
X1393904Y1070178D03*
X1388353Y1066974D03*
X1395754Y1099017D03*
X1390203Y1095813D03*
X1406420Y873810D03*
Y905853D03*
X1411971Y934691D03*
X1406420Y925079D03*
Y931488D03*
X1411971Y928283D03*
X1403154Y1041340D03*
X1408703Y1057361D03*
Y1063770D03*
X1399453Y1054157D03*
X1405004Y1050952D03*
X1401304Y1063770D03*
X1399453Y1073383D03*
X1405004Y1070178D03*
X1430471Y909057D03*
X1424921Y905853D03*
X1415671Y909057D03*
X1421222Y912262D03*
X1424921Y918670D03*
X1430471Y915466D03*
X1424921Y931488D03*
X1419371Y928283D03*
X1424921Y925079D03*
X1419371Y934691D03*
X1425353Y1054157D03*
X1425355Y1060565D03*
X1430903Y1050952D03*
X1430904Y1057361D03*
X1427203Y1076587D03*
X1427204Y1070178D03*
X1447120Y899445D03*
X1443420Y912262D03*
X1437871Y909057D03*
X1436020Y918670D03*
X1443420Y905853D03*
X1441571Y921875D03*
X1447553Y1041340D03*
X1436453Y1047750D03*
X1443853D03*
X1432753Y1041340D03*
X1440153D03*
Y1054157D03*
X1436453Y1060565D03*
Y1073383D03*
Y1066974D03*
X1442002Y1070178D03*
X1447553Y1066974D03*
X1452671Y896240D03*
X1454521Y918670D03*
X1454522Y912262D03*
X1448970Y915466D03*
X1454520Y905853D03*
X1456370Y960326D03*
X1458220Y982756D03*
X1454521Y969939D03*
X1451253Y1047749D03*
X1454953Y1034931D03*
X1453104Y1076587D03*
Y1070178D03*
X1458653Y1073383D03*
X1506320Y893036D03*
X1611475Y1259227D03*
X1714440Y1255381D03*
X1821083Y1252034D03*
G54D13*
X44396Y444564D03*
Y442989D03*
Y441415D03*
Y439840D03*
X50696D03*
Y441415D03*
Y442989D03*
Y444564D03*
X550700Y114289D03*
Y112714D03*
Y111140D03*
Y109565D03*
X557000D03*
Y111140D03*
Y112714D03*
Y114289D03*
G54D41*
X349187Y710632D03*
X351746D03*
X354305D03*
Y718112D03*
X351746D03*
X349187D03*
X1434597Y717132D03*
X1437156D03*
X1439715D03*
Y724612D03*
X1437156D03*
X1434597D03*
X1709521Y185170D03*
X1712080D03*
X1714639D03*
Y192650D03*
X1712080D03*
X1709521D03*
G54D14*
X30771Y441130D03*
Y445519D03*
X40084Y722374D03*
Y726874D03*
X37861Y1254400D03*
X62327Y393079D03*
X62329Y388462D03*
X48384Y722374D03*
Y726874D03*
X68300Y754726D03*
Y759246D03*
X67793Y1254593D03*
X104966Y493474D03*
Y513374D03*
X97228Y1254464D03*
X117516Y642762D03*
X114963Y657550D03*
X114999Y646327D03*
X114963Y651734D03*
X126694Y1254528D03*
X135707Y652919D03*
Y656431D03*
X132389Y1242353D03*
X144063Y493640D03*
Y501640D03*
Y497640D03*
Y505550D03*
X144013Y518810D03*
Y514980D03*
X154505Y1253412D03*
X147915Y1252964D03*
X148506Y1407778D03*
X192036Y681062D03*
X186270Y1255943D03*
X203056Y565982D03*
X204652Y600801D03*
X204562Y634882D03*
X208935Y1244936D03*
X210770Y572619D03*
Y606619D03*
Y640619D03*
X216154Y1255944D03*
X241393Y704825D03*
X226396Y1242283D03*
X258997Y64455D03*
X258949Y60345D03*
X258952Y56160D03*
X302227Y177279D03*
Y181279D03*
X320361Y205049D03*
X351513Y705965D03*
X393425Y1404085D03*
Y1407605D03*
X417563Y929166D03*
X435000Y1415275D03*
X434990Y1407789D03*
X437516Y380862D03*
X437970Y1420659D03*
X448790Y1407229D03*
X437455Y1411504D03*
X446486Y1424269D03*
X447876Y1626352D03*
X453896Y1401282D03*
X477973Y1398402D03*
X479452Y1394447D03*
X536341Y112592D03*
X593238Y740955D03*
X586228Y740985D03*
X614973Y400149D03*
Y404179D03*
X611874Y939877D03*
X616736Y38702D03*
X625599Y146942D03*
X625597Y151559D03*
X631736Y431062D03*
Y457862D03*
Y477862D03*
Y472862D03*
Y467862D03*
Y462862D03*
X616736Y467862D03*
X631736Y487862D03*
Y482862D03*
X623308Y1257336D03*
Y1253293D03*
X646736Y421362D03*
Y438862D03*
Y472862D03*
Y477862D03*
Y467862D03*
Y482862D03*
X663236Y408362D03*
Y404362D03*
X656304Y1252895D03*
X677044Y35067D03*
X679811Y408362D03*
Y404362D03*
X688568Y779977D03*
X691316Y1257062D03*
X699736Y408362D03*
Y404362D03*
X701736Y1301162D03*
Y1297162D03*
X704658Y1563733D03*
X704628Y1587683D03*
Y1591683D03*
X706228Y1601983D03*
X708612Y1663842D03*
X708625Y1667841D03*
X717736Y408362D03*
Y404362D03*
X719035Y1253356D03*
X719668Y1569493D03*
X726768D03*
X740506Y412692D03*
X754393Y273399D03*
X757555Y286632D03*
X759856Y474862D03*
X750676Y1256762D03*
X775736Y423212D03*
Y418212D03*
X774856Y474862D03*
X762923Y761555D03*
X793640Y763996D03*
X786043Y759655D03*
X793643Y758455D03*
X786043Y763855D03*
X778384Y1253277D03*
X798015Y295488D03*
X801185Y312773D03*
X797915Y303188D03*
X802193Y763915D03*
Y759665D03*
X807849Y1253512D03*
X824383Y760215D03*
X824480Y764316D03*
X842736Y220362D03*
X840413Y770025D03*
X839386Y1252392D03*
X849636Y216362D03*
X849736Y209362D03*
X930111Y189386D03*
X930311Y193386D03*
X928441Y201612D03*
X934905Y493701D03*
X930681Y512098D03*
X933186Y521348D03*
X931156Y980462D03*
X931294Y986143D03*
X970366Y380952D03*
X966372Y390302D03*
Y394178D03*
X987275Y341799D03*
X987395Y421961D03*
X999575Y341829D03*
X1001762Y419162D03*
X1018016Y380862D03*
Y385862D03*
Y394362D03*
Y398362D03*
X1015779Y416974D03*
X1013921Y1254263D03*
X1043423Y1254713D03*
X1073120Y1254504D03*
X1116923Y1257449D03*
X1133064Y1259862D03*
X1146493Y606082D03*
X1146503Y599122D03*
X1171516Y1016362D03*
X1192017Y1256140D03*
X1208609Y120962D03*
X1216051Y121002D03*
X1201624Y588714D03*
X1217024Y1256789D03*
X1228609Y129962D03*
Y140962D03*
Y144962D03*
X1229139Y152612D03*
X1226236Y205862D03*
Y217862D03*
Y209862D03*
Y213862D03*
X1239109Y201462D03*
Y205462D03*
Y209462D03*
Y213462D03*
X1239793Y907485D03*
X1256923Y741785D03*
X1270174Y235206D03*
X1282789Y190387D03*
X1284909Y276407D03*
X1302036Y99262D03*
X1312638Y177016D03*
X1321966Y167472D03*
X1322036Y171277D03*
X1315951Y198088D03*
X1315826Y193002D03*
X1315951Y202141D03*
X1323299Y741707D03*
X1342107Y124718D03*
X1349108Y120618D03*
X1356078Y124123D03*
X1377094Y1330133D03*
X1390453Y223754D03*
X1387021Y235188D03*
X1393975Y928806D03*
X1409257Y1330159D03*
X1411141Y1415275D03*
X1411131Y1407789D03*
X1428816Y1401948D03*
X1425931Y1408229D03*
X1413596Y1411504D03*
X1414111Y1420659D03*
X1422497Y1424249D03*
X1437213Y712575D03*
X1441234Y1330312D03*
X1438776Y1570772D03*
X1453236Y145362D03*
X1446463Y746305D03*
X1464736Y169862D03*
X1502492Y741315D03*
X1499358Y745240D03*
X1514816Y312712D03*
X1589094Y211526D03*
X1589078Y231490D03*
X1609530Y1254944D03*
X1636630Y1254844D03*
X1654809Y522176D03*
X1654745Y540071D03*
X1661966Y607332D03*
X1666430Y1255044D03*
X1686193Y466950D03*
X1681454Y488288D03*
X1685185Y502279D03*
X1693792Y521507D03*
Y525507D03*
Y541507D03*
Y529507D03*
Y533507D03*
Y545507D03*
X1696030Y1254244D03*
X1718877Y475752D03*
Y472252D03*
Y479252D03*
X1732310Y61639D03*
X1732358Y65749D03*
X1725630Y1254344D03*
X1755130D03*
X1771891Y173903D03*
Y178303D03*
X1785330Y1254744D03*
X1792486Y1505652D03*
X1803336Y1256426D03*
G54D23*
X57646Y12480D03*
X137272D03*
X186622D03*
X266858D03*
X315598D03*
X502528Y33268D03*
X582154D03*
X631504D03*
X711740D03*
X760480D03*
X1532055Y12480D03*
X1611681D03*
X1661031D03*
X1741267D03*
X1790007D03*
G54D32*
X163527Y1351890D03*
Y1377086D03*
X201927Y1351890D03*
Y1377086D03*
X349753Y1286498D03*
Y1311694D03*
X411380Y1274780D03*
Y1299976D03*
X447551Y1274792D03*
Y1299988D03*
X510022Y1286306D03*
Y1311502D03*
X677107Y1351915D03*
Y1377111D03*
X716004Y1351915D03*
Y1377111D03*
X1136799Y1389120D03*
Y1414316D03*
X1175696Y1389120D03*
Y1414316D03*
X1326294Y1287458D03*
Y1312654D03*
X1387521Y1274280D03*
Y1299476D03*
X1423692Y1274292D03*
Y1299488D03*
X1486163Y1286306D03*
Y1311502D03*
X1638273Y1384661D03*
Y1409857D03*
X1677170Y1384661D03*
Y1409857D03*
G54D50*
X500554Y98629D03*
Y108275D03*
X501932Y98629D03*
X503310D03*
X504688D03*
X506066D03*
Y108275D03*
X504688D03*
X503310D03*
X501932D03*
G54D51*
X503310Y103452D03*
G54D42*
X396332Y828421D03*
X402132D03*
X396332Y834842D03*
X402132D03*
X423955Y1646993D03*
X429755D03*
X423965Y1642006D03*
X429765D03*
X451395Y1636501D03*
X445595D03*
X661820Y399862D03*
X666870Y197272D03*
X672670D03*
X667620Y399862D03*
X678395D03*
X684195D03*
X698320D03*
X704120D03*
X710120Y493362D03*
X704320D03*
X716320Y399862D03*
X722120D03*
X742620D03*
X736820D03*
X919269Y475794D03*
X925069D03*
X932094Y477311D03*
X937894D03*
X990600Y396117D03*
X996400D03*
X1027241Y397305D03*
X1033041D03*
X1026139Y412728D03*
X1031939D03*
X1168462Y190588D03*
X1168140Y197742D03*
Y205842D03*
X1174262Y190588D03*
X1173940Y197742D03*
Y205842D03*
X1187460Y185582D03*
X1193260D03*
X1186938Y214133D03*
X1192738D03*
X1186938Y208733D03*
X1192738D03*
X1250101Y256098D03*
X1255901D03*
X1372473Y834841D03*
X1378273D03*
X1372473Y828420D03*
X1378273D03*
X1371226Y1406454D03*
X1377026D03*
X1392750Y230152D03*
X1386950D03*
G54D60*
X810850Y763874D03*
Y761315D03*
Y758756D03*
X818724D03*
Y761315D03*
Y763874D03*
X833120Y764094D03*
Y761535D03*
Y758976D03*
X840994D03*
Y761535D03*
Y764094D03*
G54D33*
X164686Y394320D03*
D03*
Y391170D03*
Y397470D03*
X753835Y309670D03*
Y306520D03*
Y312820D03*
Y309670D03*
X1288020Y267477D03*
Y270627D03*
G54D24*
X57544Y397012D03*
X53738Y396986D03*
X60761Y435475D03*
X56722Y435542D03*
X61775Y1244977D03*
X65397Y381644D03*
X69998Y381753D03*
X73281Y693127D03*
X91123Y1244051D03*
X94700Y1539788D03*
X95876Y690719D03*
X125760Y653056D03*
X135950Y1254658D03*
X159197Y1234212D03*
X173865Y1240342D03*
X201360Y669758D03*
X219272Y759901D03*
X241160Y1245008D03*
X254122Y33886D03*
X246220Y33878D03*
X250220D03*
X242220D03*
X246859Y60602D03*
X250859Y60612D03*
X250457Y758101D03*
X254477Y758211D03*
X273046Y720185D03*
Y729980D03*
X273246Y749680D03*
X286720Y42878D03*
X277046Y720185D03*
X281046Y729980D03*
X277046D03*
Y740480D03*
X281046D03*
X285046D03*
X281046Y749480D03*
X277046D03*
X285046D03*
X275639Y863963D03*
X274693Y1252002D03*
X291520Y15253D03*
X302720Y42878D03*
X294720D03*
X298211Y177795D03*
X290953Y714341D03*
X292706Y749324D03*
X300839Y1308072D03*
X316345Y205140D03*
X318158Y228503D03*
X316656Y730304D03*
X320656D03*
X312656Y723304D03*
X307967Y723360D03*
X317967Y749831D03*
X334546Y738814D03*
X332656Y723304D03*
X324656D03*
X351946Y722988D03*
X348037Y722991D03*
X344440Y742288D03*
X355946Y722991D03*
X366902Y749324D03*
X374902D03*
X387810Y1660548D03*
X391880Y1660508D03*
X436514Y1636433D03*
X440280Y1636503D03*
X499590Y88258D03*
X498730Y122638D03*
X498630Y143248D03*
X503100Y81208D03*
X507310Y81178D03*
X503270Y122648D03*
X507320Y122698D03*
X503290Y143238D03*
X507360Y143208D03*
X525900Y104316D03*
X548609Y35378D03*
X545450Y88843D03*
X541370D03*
X563100Y52698D03*
X581520Y52778D03*
X576200Y52738D03*
X571580Y52698D03*
X598405D03*
X594097D03*
X592076Y747981D03*
X610970Y52708D03*
X606330Y52698D03*
X602350D03*
X614750Y750481D03*
X603276Y747981D03*
X620097Y52698D03*
X631060Y48808D03*
X619090Y42808D03*
X620814Y155492D03*
X617008Y155466D03*
X645083Y33622D03*
X635000Y51378D03*
X639000D03*
X633603Y163212D03*
X644335Y1253309D03*
X654196Y1244943D03*
X670080Y52698D03*
X678050D03*
X674080D03*
X667347Y758401D03*
X672537Y758461D03*
X694400Y52698D03*
X681980D03*
X682588Y87353D03*
X682440Y115886D03*
X689663Y404415D03*
X684705Y1248476D03*
X698597Y52698D03*
X707597D03*
X711867Y52738D03*
X702790Y52688D03*
X712000Y72178D03*
X700960Y128218D03*
X710433Y412375D03*
X702062Y1254510D03*
X712298Y1605818D03*
X708175Y1605827D03*
X704219Y1634867D03*
X705083Y1661009D03*
X728000Y78378D03*
X719967Y72178D03*
X723957D03*
X715990D03*
X714427Y1247591D03*
X720112Y1604249D03*
X731069Y1230732D03*
X730328Y1254514D03*
X734111Y1254535D03*
X744022Y1246023D03*
X748178Y404935D03*
X772570Y1246028D03*
X762670Y1666505D03*
X791685Y1254410D03*
X808220Y140078D03*
X808843Y425645D03*
X803116Y1244133D03*
X821120Y139478D03*
X819401Y1253010D03*
X820110Y1243628D03*
X841720Y212878D03*
X837500Y223168D03*
X840651Y1236902D03*
X847271Y1253739D03*
X849767Y1246806D03*
X922320Y1663878D03*
X918300Y1663916D03*
X932487Y486199D03*
X928958Y484554D03*
X939970Y520204D03*
X924761Y520055D03*
X928393Y518607D03*
X934020Y991088D03*
X938220Y1663778D03*
X926120Y1663878D03*
X933979Y1663843D03*
X929979Y1663878D03*
X943369Y505094D03*
X946100Y1663816D03*
X942100D03*
X950100D03*
X953900D03*
X964347Y503807D03*
X968355Y503754D03*
X965570Y1559276D03*
X985445Y175599D03*
X988219Y412912D03*
X984254D03*
X1004189Y401214D03*
X1012942Y295086D03*
X1008942D03*
X1017720Y307878D03*
X1013720D03*
X1009334Y401183D03*
X1013105Y401226D03*
X1037000Y293528D03*
X1052504Y1254177D03*
X1082030Y1254368D03*
X1111904Y1254211D03*
X1135339Y1234212D03*
X1135687Y1585254D03*
X1131687D03*
X1149903Y1247350D03*
X1145687Y1585254D03*
X1141687D03*
X1151687D03*
X1153467Y589038D03*
X1166077Y763341D03*
X1165095Y1585254D03*
X1155687D03*
X1161095D03*
X1160310Y1628276D03*
X1177677Y761011D03*
X1172649Y1254378D03*
X1179563Y1247507D03*
X1175095Y1585254D03*
X1171095D03*
X1200497Y765131D03*
X1195097D03*
Y756223D03*
X1199597Y756195D03*
X1199679Y1254665D03*
X1208537Y748321D03*
X1212537D03*
X1209247Y765121D03*
X1212937Y756821D03*
X1208937D03*
X1204497Y765131D03*
X1209315Y1247754D03*
X1223793Y1236902D03*
X1230681Y1246806D03*
X1223793Y1243902D03*
X1230681Y1254694D03*
X1242398Y751333D03*
X1246260Y760481D03*
X1262383Y103676D03*
X1260514Y221398D03*
X1259998Y732533D03*
X1263787Y732531D03*
X1252847Y745511D03*
X1250260Y760481D03*
X1276345Y99646D03*
X1279485Y110541D03*
X1274257Y740581D03*
X1276980Y1304133D03*
X1275856Y1352563D03*
X1272346D03*
X1291704Y103247D03*
X1295807Y112109D03*
X1295947Y732241D03*
X1289817Y741086D03*
X1303220Y107578D03*
X1310150Y129120D03*
X1309228Y122084D03*
X1314269Y122129D03*
X1303728Y127306D03*
X1300317Y737411D03*
X1308847Y749811D03*
X1305277D03*
X1328946Y131296D03*
X1319288Y122118D03*
X1327428Y123293D03*
X1317891Y129119D03*
X1323493Y129246D03*
X1322477Y176192D03*
X1330773Y198039D03*
X1322522Y189986D03*
X1321816Y726185D03*
X1330328Y738658D03*
X1320032Y749811D03*
X1316307D03*
X1332886Y126223D03*
X1336930Y124223D03*
X1334814Y198039D03*
X1335120Y209035D03*
X1338495Y749317D03*
X1334641Y749525D03*
X1445018Y724504D03*
X1458818D03*
X1449118D03*
X1453218D03*
X1459431Y1395911D03*
X1468947Y738651D03*
X1470656Y749317D03*
X1474656D03*
X1463249Y1395911D03*
X1482751Y749318D03*
X1502396Y731343D03*
X1507016Y734482D03*
X1499245Y749781D03*
X1494963Y749678D03*
X1510437Y313841D03*
X1521975Y749781D03*
X1517575D03*
X1534000Y126878D03*
X1527185Y749781D03*
X1561890Y198768D03*
X1562890Y240438D03*
X1573507Y749601D03*
X1577507D03*
X1590915Y765721D03*
X1582017Y893099D03*
Y907761D03*
X1602650Y1254739D03*
Y1247536D03*
X1616114Y1254060D03*
X1631545Y1245059D03*
X1654143Y1250701D03*
X1661120Y614178D03*
X1675414Y1254060D03*
X1690560Y427128D03*
X1699720Y490378D03*
X1694339Y491294D03*
X1702067Y695981D03*
X1705029Y1226326D03*
X1705013Y1253905D03*
X1690518Y1248096D03*
X1712820Y172296D03*
X1705720Y490378D03*
X1711720D03*
X1705896Y706463D03*
X1706017Y695981D03*
X1713606Y710953D03*
X1709013Y1253905D03*
X1705803Y1246953D03*
X1720183Y1249890D03*
X1734714Y1254160D03*
X1749690Y1245402D03*
X1769900Y40225D03*
X1762075D03*
X1770566Y300475D03*
X1764680Y306058D03*
X1764514Y1254060D03*
X1773791Y31370D03*
X1777754Y40385D03*
X1781990Y40271D03*
X1773554Y40225D03*
X1774537Y300560D03*
X1779319Y303696D03*
X1778789Y1247161D03*
X1787706Y50056D03*
X1791706D03*
X1797417Y1237906D03*
Y1244906D03*
X1816360Y1237777D03*
X1816612Y1253601D03*
X1810954Y1252880D03*
G54D15*
X33738Y441130D03*
Y445519D03*
X43051Y722374D03*
Y726874D03*
X40828Y1254400D03*
X51351Y722374D03*
Y726874D03*
X65294Y393079D03*
X65296Y388462D03*
X71267Y754726D03*
Y759246D03*
X70760Y1254593D03*
X107933Y493474D03*
Y513374D03*
X100195Y1254464D03*
X120483Y642762D03*
X117930Y657550D03*
X117966Y646327D03*
X117930Y651734D03*
X138674Y652919D03*
Y656431D03*
X135356Y1242353D03*
X129661Y1254528D03*
X147030Y493640D03*
Y501640D03*
Y497640D03*
Y505550D03*
X146980Y518810D03*
Y514980D03*
X157472Y1253412D03*
X150882Y1252964D03*
X151473Y1407778D03*
X189237Y1255943D03*
X206023Y565982D03*
X207619Y600801D03*
X207529Y634882D03*
X195003Y681062D03*
X213737Y572619D03*
Y606619D03*
Y640619D03*
X219121Y1255944D03*
X211902Y1244936D03*
X229363Y1242283D03*
X244360Y704825D03*
X261964Y64455D03*
X261916Y60345D03*
X261919Y56160D03*
X305194Y177279D03*
Y181279D03*
X323328Y205049D03*
X354480Y705965D03*
X396392Y1404085D03*
Y1407605D03*
X420530Y929166D03*
X440483Y380862D03*
X440937Y1420659D03*
X451757Y1407229D03*
X440422Y1411504D03*
X437967Y1415275D03*
X437957Y1407789D03*
X449453Y1424269D03*
X450843Y1626352D03*
X456863Y1401282D03*
X480940Y1398402D03*
X482419Y1394447D03*
X539308Y112592D03*
X596205Y740955D03*
X589195Y740985D03*
X614841Y939877D03*
X619703Y38702D03*
X628566Y146942D03*
X628564Y151559D03*
X617940Y400149D03*
Y404179D03*
X619703Y467862D03*
X626275Y1257336D03*
Y1253293D03*
X634703Y431062D03*
Y457862D03*
Y477862D03*
Y472862D03*
Y467862D03*
Y462862D03*
Y487862D03*
Y482862D03*
X649703Y421362D03*
Y438862D03*
Y472862D03*
Y477862D03*
Y467862D03*
Y482862D03*
X659271Y1252895D03*
X680011Y35067D03*
X666203Y408362D03*
Y404362D03*
X682778Y408362D03*
Y404362D03*
X691535Y779977D03*
X694283Y1257062D03*
X702703Y408362D03*
Y404362D03*
X704703Y1301162D03*
Y1297162D03*
X707625Y1563733D03*
X707595Y1587683D03*
Y1591683D03*
X709195Y1601983D03*
X711579Y1663842D03*
X711592Y1667841D03*
X720703Y408362D03*
Y404362D03*
X722002Y1253356D03*
X722635Y1569493D03*
X743473Y412692D03*
X729735Y1569493D03*
X757360Y273399D03*
X760522Y286632D03*
X753643Y1256762D03*
X762823Y474862D03*
X777823D03*
X765890Y761555D03*
X778703Y423212D03*
Y418212D03*
X789010Y759655D03*
Y763855D03*
X781351Y1253277D03*
X800982Y295488D03*
X804152Y312773D03*
X800882Y303188D03*
X805160Y763915D03*
Y759665D03*
X796607Y763996D03*
X796610Y758455D03*
X810816Y1253512D03*
X827350Y760215D03*
X827447Y764316D03*
X843380Y770025D03*
X842353Y1252392D03*
X852603Y216362D03*
X852703Y209362D03*
X845703Y220362D03*
X933078Y189386D03*
X933278Y193386D03*
X931408Y201612D03*
X937872Y493701D03*
X933648Y512098D03*
X936153Y521348D03*
X934123Y980462D03*
X934261Y986143D03*
X973333Y380952D03*
X969339Y390302D03*
Y394178D03*
X1002542Y341829D03*
X990242Y341799D03*
X990362Y421961D03*
X1004729Y419162D03*
X1020983Y380862D03*
Y385862D03*
Y394362D03*
Y398362D03*
X1018746Y416974D03*
X1016888Y1254263D03*
X1046390Y1254713D03*
X1076087Y1254504D03*
X1119890Y1257449D03*
X1136031Y1259862D03*
X1149460Y606082D03*
X1149470Y599122D03*
X1174483Y1016362D03*
X1194984Y1256140D03*
X1211576Y120962D03*
X1204591Y588714D03*
X1231576Y129962D03*
X1219018Y121002D03*
X1231576Y140962D03*
Y144962D03*
X1232106Y152612D03*
X1229203Y205862D03*
Y217862D03*
Y209862D03*
Y213862D03*
X1219991Y1256789D03*
X1242076Y201462D03*
Y205462D03*
Y209462D03*
Y213462D03*
X1242760Y907485D03*
X1259890Y741785D03*
X1273141Y235206D03*
X1285756Y190387D03*
X1287876Y276407D03*
X1305003Y99262D03*
X1324933Y167472D03*
X1315605Y177016D03*
X1325003Y171277D03*
X1318918Y198088D03*
X1318793Y193002D03*
X1318918Y202141D03*
X1326266Y741707D03*
X1345074Y124718D03*
X1352075Y120618D03*
X1359045Y124123D03*
X1380061Y1330133D03*
X1393420Y223754D03*
X1389988Y235188D03*
X1396942Y928806D03*
X1412224Y1330159D03*
X1414108Y1415275D03*
X1414098Y1407789D03*
X1428898Y1408229D03*
X1416563Y1411504D03*
X1417078Y1420659D03*
X1425464Y1424249D03*
X1440180Y712575D03*
X1444201Y1330312D03*
X1431783Y1401948D03*
X1441743Y1570772D03*
X1456203Y145362D03*
X1449430Y746305D03*
X1467703Y169862D03*
X1505459Y741315D03*
X1502325Y745240D03*
X1517783Y312712D03*
X1592061Y211526D03*
X1592045Y231490D03*
X1612497Y1254944D03*
X1639597Y1254844D03*
X1657776Y522176D03*
X1657712Y540071D03*
X1664933Y607332D03*
X1669397Y1255044D03*
X1689160Y466950D03*
X1684421Y488288D03*
X1688152Y502279D03*
X1696759Y521507D03*
Y525507D03*
Y541507D03*
Y529507D03*
Y533507D03*
Y545507D03*
X1698997Y1254244D03*
X1721844Y475752D03*
Y472252D03*
Y479252D03*
X1735277Y61639D03*
X1735325Y65749D03*
X1728597Y1254344D03*
X1758097D03*
X1774858Y173903D03*
Y178303D03*
X1788297Y1254744D03*
X1795453Y1505652D03*
X1806303Y1256426D03*
G54D61*
X859100Y769165D03*
Y765425D03*
Y761685D03*
X849454D03*
Y769165D03*
G54D52*
X517115Y107550D03*
Y111060D03*
X520265Y107550D03*
Y111060D03*
X931426Y527751D03*
X934576D03*
X931426D03*
X928276D03*
X931503Y533077D03*
X934653D03*
X931503D03*
X928353D03*
X1011630Y218253D03*
X1014780D03*
X1011630D03*
X1008480D03*
X1330873Y542647D03*
D03*
X1327723D03*
X1330796Y537321D03*
D03*
X1327646D03*
X1334023Y542647D03*
X1333946Y537321D03*
G54D43*
X387842Y1593517D03*
Y1591417D03*
X391417Y1593517D03*
Y1591417D03*
X663561Y38286D03*
Y36186D03*
X666889Y38287D03*
Y36187D03*
X1327633Y252162D03*
Y254262D03*
X1343782Y243266D03*
Y245366D03*
X1340182Y243266D03*
Y245366D03*
X1339990Y260466D03*
Y262566D03*
X1336390Y260466D03*
Y262566D03*
X1331233Y252162D03*
Y254262D03*
X1347448Y251266D03*
Y253366D03*
X1353702Y243266D03*
Y245366D03*
X1357302Y243266D03*
Y245366D03*
X1360450Y251266D03*
Y253366D03*
X1351048Y251266D03*
Y253366D03*
X1364050Y251266D03*
Y253366D03*
G54D25*
X57544Y399979D03*
X53738Y399953D03*
X60761Y438442D03*
X56722Y438509D03*
X61775Y1247944D03*
X65397Y384611D03*
X69998Y384720D03*
X73281Y696094D03*
X91123Y1247018D03*
X94700Y1542755D03*
X95876Y693686D03*
X125760Y656023D03*
X135950Y1257625D03*
X159197Y1237179D03*
X173865Y1243309D03*
X201360Y672725D03*
X219272Y762868D03*
X241160Y1247975D03*
X254122Y36853D03*
X246220Y36845D03*
X250220D03*
X242220D03*
X246859Y63569D03*
X250859Y63579D03*
X250457Y761068D03*
X254477Y761178D03*
X273046Y723152D03*
Y732947D03*
X273246Y752647D03*
X286720Y45845D03*
X281046Y732947D03*
X277046Y723152D03*
Y732947D03*
Y743447D03*
X281046D03*
X285046D03*
X281046Y752447D03*
X277046D03*
X285046D03*
X275639Y866930D03*
X274693Y1254969D03*
X291520Y18220D03*
X302720Y45845D03*
X294720D03*
X298211Y180762D03*
X290953Y717308D03*
X292706Y752291D03*
X300839Y1311039D03*
X316345Y208107D03*
X318158Y231470D03*
X316656Y733271D03*
X320656D03*
X312656Y726271D03*
X307967Y726327D03*
X317967Y752798D03*
X332656Y726271D03*
X324656D03*
X334546Y741781D03*
X351946Y725955D03*
X348037Y725958D03*
X344440Y745255D03*
X355946Y725958D03*
X366902Y752291D03*
X374902D03*
X387810Y1663515D03*
X391880Y1663475D03*
X436514Y1639400D03*
X440280Y1639470D03*
X499590Y91225D03*
X498730Y125605D03*
X498630Y146215D03*
X503100Y84175D03*
X507310Y84145D03*
X503270Y125615D03*
X507320Y125665D03*
X503290Y146205D03*
X507360Y146175D03*
X525900Y107283D03*
X548609Y38345D03*
X545450Y91810D03*
X541370D03*
X563100Y55665D03*
X581520Y55745D03*
X576200Y55705D03*
X571580Y55665D03*
X598405D03*
X594097D03*
X592076Y750948D03*
X610970Y55675D03*
X606330Y55665D03*
X602350D03*
X614750Y753448D03*
X603276Y750948D03*
X620097Y55665D03*
X631060Y51775D03*
X619090Y45775D03*
X620814Y158459D03*
X617008Y158433D03*
X645083Y36589D03*
X635000Y54345D03*
X639000D03*
X633603Y166179D03*
X644335Y1256276D03*
X654196Y1247910D03*
X670080Y55665D03*
X678050D03*
X674080D03*
X667347Y761368D03*
X672537Y761428D03*
X694400Y55665D03*
X681980D03*
X682588Y90320D03*
X682440Y118853D03*
X689663Y407382D03*
X684705Y1251443D03*
X698597Y55665D03*
X707597D03*
X711867Y55705D03*
X702790Y55655D03*
X712000Y75145D03*
X700960Y131185D03*
X710433Y415342D03*
X702062Y1257477D03*
X712298Y1608785D03*
X708175Y1608794D03*
X704219Y1637834D03*
X705083Y1663976D03*
X728000Y81345D03*
X719967Y75145D03*
X723957D03*
X715990D03*
X714427Y1250558D03*
X720112Y1607216D03*
X731069Y1233699D03*
X730328Y1257481D03*
X734111Y1257502D03*
X744022Y1248990D03*
X748178Y407902D03*
X772570Y1248995D03*
X762670Y1669472D03*
X791685Y1257377D03*
X808220Y143045D03*
X808843Y428612D03*
X803116Y1247100D03*
X821120Y142445D03*
X819401Y1255977D03*
X820110Y1246595D03*
X841720Y215845D03*
X837500Y226135D03*
X840651Y1239869D03*
X847271Y1256706D03*
X849767Y1249773D03*
X922320Y1666845D03*
X918300Y1666883D03*
X932487Y489166D03*
X928958Y487521D03*
X939970Y523171D03*
X924761Y523022D03*
X928393Y521574D03*
X934020Y994055D03*
X938220Y1666745D03*
X926120Y1666845D03*
X933979Y1666810D03*
X929979Y1666845D03*
X943369Y508061D03*
X946100Y1666783D03*
X942100D03*
X950100D03*
X953900D03*
X964347Y506774D03*
X968355Y506721D03*
X965570Y1562243D03*
X985445Y178566D03*
X988219Y415879D03*
X984254D03*
X1004189Y404181D03*
X1012942Y298053D03*
X1008942D03*
X1017720Y310845D03*
X1013720D03*
X1009334Y404150D03*
X1013105Y404193D03*
X1037000Y296495D03*
X1052504Y1257144D03*
X1082030Y1257335D03*
X1111904Y1257178D03*
X1135339Y1237179D03*
X1135687Y1588221D03*
X1131687D03*
X1149903Y1250317D03*
X1145687Y1588221D03*
X1141687D03*
X1151687D03*
X1153467Y592005D03*
X1166077Y766308D03*
X1165095Y1588221D03*
X1155687D03*
X1161095D03*
X1160310Y1631243D03*
X1177677Y763978D03*
X1172649Y1257345D03*
X1179563Y1250474D03*
X1175095Y1588221D03*
X1171095D03*
X1200497Y768098D03*
X1195097D03*
Y759190D03*
X1199597Y759162D03*
X1199679Y1257632D03*
X1208537Y751288D03*
X1212537D03*
X1209247Y768088D03*
X1212937Y759788D03*
X1208937D03*
X1204497Y768098D03*
X1209315Y1250721D03*
X1223793Y1239869D03*
X1230681Y1249773D03*
X1223793Y1246869D03*
X1230681Y1257661D03*
X1242398Y754300D03*
X1246260Y763448D03*
X1262383Y106643D03*
X1260514Y224365D03*
X1259998Y735500D03*
X1263787Y735498D03*
X1252847Y748478D03*
X1250260Y763448D03*
X1276345Y102613D03*
X1279485Y113508D03*
X1274257Y743548D03*
X1276980Y1307100D03*
X1275856Y1355530D03*
X1272346D03*
X1295807Y115076D03*
X1291704Y106214D03*
X1295947Y735208D03*
X1289817Y744053D03*
X1303220Y110545D03*
X1310150Y132087D03*
X1309228Y125051D03*
X1314269Y125096D03*
X1303728Y130273D03*
X1308847Y752778D03*
X1305277D03*
X1300317Y740378D03*
X1328946Y134263D03*
X1319288Y125085D03*
X1327428Y126260D03*
X1317891Y132086D03*
X1323493Y132213D03*
X1322477Y179159D03*
X1330773Y201006D03*
X1322522Y192953D03*
X1321816Y729152D03*
X1320032Y752778D03*
X1316307D03*
X1330328Y741625D03*
X1332886Y129190D03*
X1336930Y127190D03*
X1334814Y201006D03*
X1335120Y212002D03*
X1338495Y752284D03*
X1334641Y752492D03*
X1445018Y727471D03*
X1458818D03*
X1449118D03*
X1453218D03*
X1459431Y1398878D03*
X1470656Y752284D03*
X1474656D03*
X1468947Y741618D03*
X1463249Y1398878D03*
X1482751Y752285D03*
X1502396Y734310D03*
X1507016Y737449D03*
X1499245Y752748D03*
X1494963Y752645D03*
X1510437Y316808D03*
X1521975Y752748D03*
X1517575D03*
X1534000Y129845D03*
X1527185Y752748D03*
X1561890Y201735D03*
X1562890Y243405D03*
X1573507Y752568D03*
X1577507D03*
X1590915Y768688D03*
X1582017Y896066D03*
Y910728D03*
X1602650Y1257706D03*
Y1250503D03*
X1616114Y1257027D03*
X1631545Y1248026D03*
X1654143Y1253668D03*
X1661120Y617145D03*
X1675414Y1257027D03*
X1690560Y430095D03*
X1699720Y493345D03*
X1694339Y494261D03*
X1702067Y698948D03*
X1705029Y1229293D03*
X1705013Y1256872D03*
X1690518Y1251063D03*
X1712820Y175263D03*
X1705720Y493345D03*
X1711720D03*
X1706017Y698948D03*
X1705896Y709430D03*
X1713606Y713920D03*
X1709013Y1256872D03*
X1705803Y1249920D03*
X1720183Y1252857D03*
X1734714Y1257127D03*
X1749690Y1248369D03*
X1769900Y43192D03*
X1762075D03*
X1770566Y303442D03*
X1764680Y309025D03*
X1764514Y1257027D03*
X1773791Y34337D03*
X1777754Y43352D03*
X1781990Y43238D03*
X1773554Y43192D03*
X1774537Y303527D03*
X1779319Y306663D03*
X1778789Y1250128D03*
X1787706Y53023D03*
X1791706D03*
X1797417Y1240873D03*
Y1247873D03*
X1816360Y1240744D03*
X1816612Y1256568D03*
X1810954Y1255847D03*
G54D70*
X1202549Y1249708D03*
X1265642Y143511D03*
X1263947Y148462D03*
X1266282Y156855D03*
X1269082Y153785D03*
G54D34*
X174685Y637367D03*
X174393Y668511D03*
X205159Y1430034D03*
X393067Y1354446D03*
X422833D03*
X453169D03*
X468443Y1379662D03*
X482543Y1353962D03*
X526478Y1439952D03*
X718638Y1429579D03*
X1077638Y133866D03*
X1178470Y1466363D03*
X1369208Y1353946D03*
X1398974D03*
X1429310D03*
X1444043Y1379362D03*
X1459076Y1353946D03*
X1502956Y1439530D03*
X1682882Y618174D03*
Y669109D03*
X1679944Y1463655D03*
X1769790Y194789D03*
X1799350D03*
X1836248Y269763D03*
Y299056D03*
G54D16*
X40120Y744554D03*
Y1000853D03*
Y1287664D03*
X69820Y744554D03*
Y1000853D03*
Y1287664D03*
X99520Y744554D03*
Y1000853D03*
Y1287664D03*
X129220Y744554D03*
Y1000853D03*
Y1287664D03*
X158920Y744554D03*
Y1000853D03*
Y1287664D03*
X188620Y744554D03*
Y1000853D03*
Y1287664D03*
X218320Y744554D03*
Y1000853D03*
Y1287664D03*
X248020Y744554D03*
Y1000853D03*
Y1287664D03*
X633320Y744554D03*
Y1000853D03*
Y1287664D03*
X663020Y744554D03*
Y1000853D03*
Y1287664D03*
X692720Y744554D03*
Y1000853D03*
Y1287664D03*
X722420Y744554D03*
Y1000853D03*
Y1287664D03*
X752120Y744554D03*
Y1000853D03*
Y1287664D03*
X781820Y744554D03*
Y1000853D03*
Y1287664D03*
X811520Y744554D03*
Y1000853D03*
Y1287664D03*
X841220Y744554D03*
Y1000853D03*
Y1287664D03*
X1016262Y744554D03*
Y1000853D03*
Y1287664D03*
X1045962Y744554D03*
Y1000853D03*
Y1287664D03*
X1075662Y744554D03*
Y1000853D03*
Y1287664D03*
X1105362Y744554D03*
Y1000853D03*
Y1287664D03*
X1135062Y744554D03*
Y1000853D03*
Y1287664D03*
X1164762Y744554D03*
Y1000853D03*
Y1287664D03*
X1194462Y744554D03*
Y1000853D03*
Y1287664D03*
X1224162Y744554D03*
Y1000853D03*
Y1287664D03*
X1609462Y744554D03*
Y1000853D03*
Y1287664D03*
X1639162Y744554D03*
Y1000853D03*
Y1287664D03*
X1668862Y744554D03*
Y1000853D03*
Y1287664D03*
X1698562Y744554D03*
Y1000853D03*
Y1287664D03*
X1728262Y744554D03*
Y1000853D03*
Y1287664D03*
X1757962Y744554D03*
Y1000853D03*
Y1287664D03*
X1787662Y744554D03*
Y1000853D03*
Y1287664D03*
X1817362Y744554D03*
Y1000853D03*
Y1287664D03*
G54D71*
X1249473Y140119D03*
X1249959Y153904D03*
X1252193Y137419D03*
X1256530Y160252D03*
G54D17*
X37721Y754822D03*
Y763090D03*
X54847Y754822D03*
Y763090D03*
X1446071Y732802D03*
Y741070D03*
X1463197Y732802D03*
Y741070D03*
G54D44*
X412561Y933298D03*
X417261D03*
X407861D03*
X412561Y939098D03*
X417261D03*
X407861D03*
X429628Y1631147D03*
Y1636947D03*
X438255Y1614977D03*
Y1609177D03*
X464080Y932964D03*
X468780D03*
X464080Y938764D03*
X468780D03*
X473480Y932964D03*
Y938764D03*
X686220Y490762D03*
Y484962D03*
X906493Y476404D03*
X900460Y490022D03*
X906493Y482204D03*
X900460Y495822D03*
X913401Y475904D03*
X924782Y487212D03*
Y481412D03*
X919515D03*
Y487212D03*
X913401Y481704D03*
X956708Y381166D03*
X951914Y381162D03*
X956708Y386966D03*
X951914Y386962D03*
X1031900Y418517D03*
Y424317D03*
X1282145Y260251D03*
Y266051D03*
X1276901Y260225D03*
Y266025D03*
X1313264Y227309D03*
Y233109D03*
X1307864Y227309D03*
Y233109D03*
X1323896Y227362D03*
Y233162D03*
X1318627Y227279D03*
Y233079D03*
X1362309Y217419D03*
Y211619D03*
X1373111Y217452D03*
Y211652D03*
X1367711Y217404D03*
Y211604D03*
X1388702Y932963D03*
X1393402D03*
X1384002D03*
X1388702Y938763D03*
X1393402D03*
X1384002D03*
X1440221Y932963D03*
X1444921D03*
X1440221Y938763D03*
X1444921D03*
X1449621Y932963D03*
Y938763D03*
G54D53*
X673054Y432187D03*
X669904D03*
X673054Y460533D03*
X669904D03*
X695101Y441636D03*
Y444785D03*
Y451084D03*
Y447935D03*
X698251Y441636D03*
Y444785D03*
Y451084D03*
Y447935D03*
X704550Y466832D03*
X701400D03*
X717148Y438486D03*
X713998D03*
X717148Y444785D03*
X713998D03*
X717148Y441636D03*
X713998D03*
X717148Y447935D03*
X713998D03*
X717148Y451084D03*
X713998D03*
X717148Y454234D03*
X713998D03*
G54D35*
X174685Y647210D03*
X174393Y678354D03*
X195316Y1430034D03*
X383224Y1354446D03*
X412990D03*
X443326D03*
X458600Y1379662D03*
X472700Y1353962D03*
X526478Y1449795D03*
X708795Y1429579D03*
X1168627Y1466363D03*
X1359365Y1353946D03*
X1389131D03*
X1419467D03*
X1434200Y1379362D03*
X1449233Y1353946D03*
X1502956Y1449373D03*
X1670101Y1463655D03*
X1682882Y628017D03*
Y678952D03*
X1769790Y204632D03*
X1799350D03*
X1826405Y269763D03*
Y299056D03*
G54D26*
X48333Y444958D03*
X46759D03*
Y439446D03*
X48333D03*
X553063Y109171D03*
X554637D03*
Y114683D03*
X553063D03*
G54D62*
X922441Y154311D03*
Y243799D03*
G54D72*
X1254292Y139518D03*
X1251572Y142218D03*
X1258629Y162351D03*
X1252058Y156003D03*
G54D18*
X37721Y760236D03*
Y757676D03*
X54847D03*
Y760236D03*
X1446071Y738216D03*
Y735656D03*
X1463197D03*
Y738216D03*
G54D45*
X417650Y1635132D03*
X410170D03*
X417580Y1643304D03*
X410100D03*
X937566Y382223D03*
X933830Y967442D03*
X941310D03*
X945046Y382223D03*
X1026552Y405913D03*
X1034032D03*
G54D36*
X177043Y1409115D03*
X184043D03*
X205538Y698226D03*
X219563Y586471D03*
X212563D03*
X219563Y594877D03*
X212563D03*
X219563Y620471D03*
X212563D03*
X219563Y628877D03*
X212563D03*
X219563Y654471D03*
X212563D03*
X219563Y662877D03*
X212563D03*
X212538Y698226D03*
X225113Y1409935D03*
X218113D03*
X240518Y671881D03*
X238478Y699357D03*
X255965Y70636D03*
X255669Y78930D03*
X244518Y568690D03*
X251518D03*
X244518Y602690D03*
X251518D03*
X244518Y595420D03*
X251518D03*
X244518Y636690D03*
X251518D03*
X244518Y629420D03*
X251518D03*
X247518Y671881D03*
X243218Y663720D03*
X250218D03*
X245478Y699357D03*
X262965Y70636D03*
X262669Y78930D03*
X400026Y1157520D03*
Y1165570D03*
X421252Y834842D03*
Y827536D03*
X407772D03*
X414772D03*
X407772Y834842D03*
X414772D03*
X412232Y1032870D03*
X419232D03*
X407026Y1157520D03*
X412526D03*
X419526D03*
X407026Y1165570D03*
X412526D03*
X419526D03*
X428252Y834842D03*
Y827536D03*
X434732D03*
X434729Y834842D03*
X437526Y1157520D03*
X432026D03*
X425026D03*
X432026Y1165570D03*
X425026D03*
X437526D03*
X448212Y827536D03*
X448209Y834842D03*
X441732Y827536D03*
X441729Y834842D03*
X444526Y1157520D03*
X450026D03*
X444526Y1165570D03*
X450026D03*
X461689Y834842D03*
X468689D03*
X461692Y827536D03*
X468692D03*
X455212D03*
X455209Y834842D03*
X468451Y1032870D03*
X461451D03*
X457026Y1157520D03*
X462526D03*
X469526D03*
X457026Y1165570D03*
X462526D03*
X469526D03*
X482169Y834842D03*
X475169D03*
X482172Y827536D03*
X475172D03*
X482026Y1157520D03*
X475026D03*
X482026Y1165570D03*
X475026D03*
X562617Y1321370D03*
Y1330170D03*
X569617Y1321370D03*
Y1330170D03*
X685420Y97062D03*
X692420D03*
X697662Y1409840D03*
X690662D03*
X739880Y1409905D03*
X732880D03*
X940761Y975162D03*
X933761D03*
X1069118Y269600D03*
X1068799Y280874D03*
X1076118Y269600D03*
X1075799Y280874D03*
X1150254Y1445544D03*
X1167444Y182685D03*
X1157254Y1445544D03*
X1174444Y182685D03*
X1193073Y200486D03*
X1186073D03*
X1193069Y193180D03*
X1186069D03*
X1200192Y1437872D03*
X1193192D03*
X1376167Y1157519D03*
Y1165569D03*
X1397393Y827535D03*
Y834841D03*
X1383913D03*
X1390913D03*
X1383913Y827535D03*
X1390913D03*
X1388373Y1032869D03*
X1395373D03*
X1383167Y1157519D03*
X1388667D03*
X1395667D03*
X1383167Y1165569D03*
X1388667D03*
X1395667D03*
X1410873Y827535D03*
X1410870Y834841D03*
X1404393Y827535D03*
Y834841D03*
X1408167Y1157519D03*
X1401167D03*
X1413667D03*
X1408167Y1165569D03*
X1401167D03*
X1413667D03*
X1424353Y827535D03*
X1424350Y834841D03*
X1417873Y827535D03*
X1417870Y834841D03*
X1420667Y1157519D03*
X1426167D03*
X1420667Y1165569D03*
X1426167D03*
X1437833Y827535D03*
X1444833D03*
X1437830Y834841D03*
X1444830D03*
X1431353Y827535D03*
X1431350Y834841D03*
X1444592Y1032869D03*
X1437592D03*
X1433167Y1157519D03*
X1438667D03*
X1445667D03*
X1433167Y1165569D03*
X1438667D03*
X1445667D03*
X1458310Y834841D03*
X1451310D03*
X1458313Y827535D03*
X1451313D03*
X1458167Y1157519D03*
X1451167D03*
X1458167Y1165569D03*
X1451167D03*
X1478658Y293756D03*
X1478758Y285556D03*
X1478658Y301956D03*
X1485658Y293756D03*
X1485758Y285556D03*
X1485858Y316356D03*
X1478858D03*
X1485658Y301956D03*
X1537508Y1330120D03*
Y1338920D03*
X1544508Y1330120D03*
Y1338920D03*
X1607955Y589185D03*
Y616701D03*
X1602455Y624862D03*
Y658862D03*
Y651592D03*
Y685592D03*
Y692862D03*
Y719592D03*
X1614955Y589185D03*
Y616701D03*
X1609455Y624862D03*
Y658862D03*
Y651592D03*
Y685592D03*
Y692862D03*
Y719592D03*
X1634410Y625705D03*
X1641410D03*
X1634410Y634111D03*
X1641410D03*
X1634410Y668111D03*
X1641410D03*
X1634410Y659705D03*
X1641410D03*
X1634410Y693705D03*
X1641410D03*
X1634410Y702111D03*
X1641410D03*
X1644435Y590356D03*
X1651435D03*
X1651828Y1442736D03*
X1658828D03*
X1701327Y1443735D03*
X1694327D03*
X1729326Y71930D03*
X1736326D03*
X1729130Y80364D03*
X1736130D03*
X1755271Y708121D03*
X1762477Y699940D03*
X1755477D03*
X1762271Y708121D03*
G54D54*
X676203Y444785D03*
Y447935D03*
X685652Y413289D03*
Y416439D03*
X695101Y457384D03*
Y454234D03*
X701400Y444785D03*
Y441635D03*
X704550Y444785D03*
Y441635D03*
X707699Y457384D03*
Y454234D03*
X704550Y457384D03*
Y454234D03*
X701400Y457384D03*
Y454234D03*
X698251Y457384D03*
Y454234D03*
X710849Y457384D03*
Y454234D03*
X723447Y413289D03*
Y416439D03*
G54D63*
X927154Y492103D03*
X918078Y495177D03*
X918212Y500777D03*
X926173Y512391D03*
G54D27*
X86433Y688160D03*
X95849Y716358D03*
X91610Y721414D03*
X121400Y638062D03*
X122575Y671930D03*
X149568Y1395145D03*
X152684Y1403451D03*
X190827D03*
X204610Y605097D03*
Y639097D03*
X249885Y69623D03*
X245220Y67862D03*
X306667Y1361597D03*
X422320Y1383862D03*
X419861Y1429718D03*
X485141Y1405430D03*
X663187Y1395170D03*
X666303Y1403476D03*
X726810Y1652430D03*
X722630Y1655740D03*
X735300Y1648760D03*
X760469Y442647D03*
X774982Y446908D03*
X769452Y1584393D03*
X812698Y1587047D03*
X854777Y1586968D03*
X877322Y296051D03*
X896672Y1587073D03*
X1012791Y157596D03*
X1084000Y1647110D03*
X1122879Y1431474D03*
X1125995Y1439780D03*
X1164138D03*
X1379192Y1325373D03*
X1393630Y1426562D03*
X1411320Y1325373D03*
X1443448D03*
X1451198Y1403047D03*
X1624353Y1428766D03*
X1627469Y1437072D03*
X1657755Y517910D03*
X1649363Y649485D03*
Y683485D03*
Y717485D03*
X1669222Y604490D03*
X1665612Y1437072D03*
X1689095Y462640D03*
X1690229Y481845D03*
X1689544Y543874D03*
X1689506Y539882D03*
X1701811Y501318D03*
X1693711Y498527D03*
X1705035Y729210D03*
X1716148Y483720D03*
X1716087Y495665D03*
X1716156Y487685D03*
X1716278Y491676D03*
X1710122Y703509D03*
G54D55*
X688802Y438486D03*
X691952D03*
X688802Y441636D03*
X691952D03*
X688802Y444785D03*
X691952D03*
X688802Y454234D03*
X691952D03*
X688802Y447935D03*
X691952D03*
X688802Y451084D03*
X691952D03*
X707699Y444785D03*
X710849D03*
X707699Y441636D03*
X710849D03*
X707699Y447935D03*
X710849D03*
X707699Y451084D03*
X710849D03*
X729747Y432187D03*
X732897D03*
X729747Y460533D03*
X732897D03*
G54D19*
X40839Y769449D03*
X74169Y381709D03*
X77121Y693098D03*
X80971D03*
X90396Y692430D03*
X109200Y637379D03*
X105400Y639579D03*
X99516Y690740D03*
X99779Y758961D03*
X103779D03*
X107779D03*
X95779D03*
X112497Y513781D03*
X112900Y637979D03*
X126092Y638660D03*
X136029Y758061D03*
X140029D03*
X140104Y1554594D03*
X144029Y758061D03*
X148029D03*
X144120Y1355829D03*
X153789Y1394443D03*
X155100Y1717599D03*
X168562Y394520D03*
X191602Y759382D03*
X187602D03*
X183602D03*
X182727Y1355718D03*
X190332Y1394418D03*
X190971Y1407687D03*
X205320Y673879D03*
X207602Y759382D03*
X203602D03*
X195602D03*
X199602D03*
X209220Y673879D03*
X211602Y759382D03*
X214580Y1355711D03*
X238063Y31270D03*
X248442Y769424D03*
X257342Y768724D03*
X245066Y1254398D03*
X269046Y720186D03*
X265043D03*
X269046Y729981D03*
X273000Y740521D03*
X268870Y744085D03*
X286046Y720186D03*
X282120Y720084D03*
X288646Y749381D03*
X295520Y15254D03*
X298720Y42879D03*
X290720D03*
X294687Y704587D03*
X301038Y720841D03*
Y713702D03*
X297087Y723934D03*
X304602Y730511D03*
X296706Y749325D03*
X300839Y1315708D03*
X306207Y1352564D03*
X302401Y1360053D03*
X306720Y42879D03*
X320656Y723305D03*
X316656D03*
X317967Y740851D03*
X338161Y715307D03*
X327096Y738815D03*
X328656Y723305D03*
X335126Y730815D03*
X336446Y749325D03*
X328620Y1305069D03*
X338300Y1329766D03*
X336179Y1337035D03*
X340446Y749325D03*
X344446D03*
X370902D03*
X362902D03*
X358902D03*
X368391Y1322448D03*
X382902Y749325D03*
X378902D03*
X386902D03*
X372428Y1316440D03*
X383740Y1660499D03*
X390820Y1278379D03*
X400462Y1322109D03*
X405156Y1316805D03*
X416127Y1408182D03*
X431728Y1322084D03*
X424320Y1402079D03*
X430910Y1402089D03*
X432851Y1618354D03*
X436701Y1316246D03*
X450294Y1417486D03*
X440270Y1619289D03*
X444600Y1619449D03*
X460800Y380079D03*
X468831Y1278008D03*
X468790Y1316208D03*
X464191Y1322109D03*
X473013Y1030141D03*
X499510Y81139D03*
X490963Y1277961D03*
X496319Y1335535D03*
X501013Y1329615D03*
X488570Y1413338D03*
X503150Y71489D03*
X507310Y71509D03*
X529720Y35379D03*
X525900Y111217D03*
X530052Y1312623D03*
X533423Y1352564D03*
X528929Y1358608D03*
X539720Y35379D03*
X534720D03*
X542530Y117249D03*
X546370D03*
X554720Y35379D03*
X572500D03*
X568500D03*
X590100Y56879D03*
X597220Y88379D03*
X592220D03*
X595597Y747947D03*
X608250Y749982D03*
X611760Y743987D03*
X599763Y747963D03*
X614750Y757482D03*
Y764482D03*
X608225Y757547D03*
X607340Y883614D03*
X631130Y55799D03*
X624831Y163149D03*
X629002Y163104D03*
X639000Y60379D03*
X635000D03*
X633673Y1253265D03*
X649047Y33627D03*
X664342Y774624D03*
X661942Y1401752D03*
X671942Y770224D03*
X667408Y1394468D03*
X685968Y52699D03*
X690220D03*
X686588Y87354D03*
X696760Y128249D03*
X688247Y381672D03*
X692247D03*
X694720Y486504D03*
X690720D03*
X693310Y757178D03*
X688967Y787509D03*
X696860Y1355997D03*
X707500Y75379D03*
X708110Y82629D03*
X703500Y75379D03*
X712100Y82629D03*
X701362Y757178D03*
X697336D03*
X705388D03*
X710688D03*
X701830Y1401712D03*
X703951Y1394443D03*
X708219Y1634868D03*
X724644Y52062D03*
X729293D03*
X719949D03*
X723400Y82579D03*
X728909Y760721D03*
X714688Y757178D03*
X718688D03*
X728199Y1355736D03*
X724452Y1584035D03*
X724392Y1604280D03*
X716202Y1604263D03*
X737595Y52062D03*
X741377D03*
X733642D03*
X745474D03*
X732501Y74965D03*
X736601D03*
X745220Y511379D03*
X736909Y760721D03*
X745009Y760781D03*
X732909Y760721D03*
X740909D03*
X749477Y52062D03*
X751220Y511379D03*
X753009Y760781D03*
X749009D03*
X757009D03*
X758758Y1666458D03*
X765188Y1585218D03*
X768714Y1666458D03*
X808797Y433442D03*
X808297Y1588300D03*
X833445Y223235D03*
X849767Y1239993D03*
X850415Y1587764D03*
X898087Y462929D03*
X902875D03*
X907420Y466079D03*
X905010Y490804D03*
X892332Y1588160D03*
X911520Y466079D03*
X916111Y509044D03*
X921149Y520073D03*
X919350Y979549D03*
X919300Y990169D03*
X914500Y1663917D03*
X937643Y511867D03*
X926380Y979699D03*
X961445Y381271D03*
X972379Y503808D03*
X960620Y503779D03*
X980092Y412913D03*
X992345D03*
X994956Y424419D03*
X1020069Y299930D03*
X1009000Y380379D03*
X1024099Y299930D03*
X1035688Y390054D03*
X1047500Y384379D03*
X1053749Y760341D03*
X1057749D03*
X1065749D03*
X1061749D03*
X1087196Y760996D03*
X1083296D03*
X1091096D03*
X1098896D03*
X1102796D03*
X1094996D03*
X1115869Y761081D03*
X1106696Y760996D03*
X1119869Y761081D03*
X1110680Y761158D03*
X1105717Y1254898D03*
X1117420Y1392330D03*
X1127869Y761081D03*
X1123869D03*
X1121753Y1438096D03*
X1127100Y1430772D03*
X1126100Y1444799D03*
X1149467Y589039D03*
X1145467D03*
X1142921Y1254694D03*
X1151687Y1577255D03*
X1141687D03*
X1145687D03*
X1153537Y603029D03*
X1153477Y596059D03*
X1163891Y1255121D03*
X1156552Y1392302D03*
X1163643Y1430747D03*
X1164172Y1444046D03*
X1161095Y1577255D03*
X1155687D03*
X1165095D03*
X1172742Y770924D03*
X1179842Y778824D03*
X1171095Y1577255D03*
X1175095D03*
X1197396Y595838D03*
Y602853D03*
X1187891Y1392041D03*
X1228704Y106079D03*
X1228860Y761282D03*
X1222707Y760442D03*
X1249122Y752924D03*
X1242260Y760482D03*
X1235360D03*
X1258195Y126354D03*
X1260544Y228039D03*
X1256193Y730682D03*
X1252847Y738312D03*
X1263937Y742482D03*
X1266723Y103677D03*
X1280291Y242631D03*
X1277257Y733502D03*
X1273257Y733582D03*
X1280797Y740482D03*
X1274198Y747608D03*
X1276980Y1311769D03*
X1282313Y1352564D03*
X1280192Y1359833D03*
X1297821Y100105D03*
X1283485Y112072D03*
X1287641D03*
X1291704Y112111D03*
X1284120Y241659D03*
X1295947Y725242D03*
X1292007Y727252D03*
X1294937Y749482D03*
X1284797Y742202D03*
X1299890Y127259D03*
X1313597Y742312D03*
X1301487Y749812D03*
X1303761Y1313069D03*
X1314441Y1329766D03*
X1312320Y1337035D03*
X1322501Y183116D03*
X1328020Y176238D03*
X1317567Y742322D03*
X1330888Y749526D03*
X1346604Y146449D03*
X1342525D03*
X1343012Y203560D03*
X1334298Y738669D03*
X1344532Y1322448D03*
X1353850Y137189D03*
X1348241Y204038D03*
X1348569Y1316440D03*
X1367420Y1278579D03*
X1381297Y1316805D03*
X1406963Y1402062D03*
X1412842Y1316246D03*
X1426435Y1417486D03*
X1444852Y1278478D03*
X1444931Y1316208D03*
X1449443Y1029830D03*
X1455734Y1395912D03*
X1469067Y731372D03*
X1466984Y1278431D03*
X1477154Y1329615D03*
X1472460Y1335535D03*
X1465747Y1413882D03*
X1478656Y749318D03*
X1490992Y749681D03*
X1486741Y749319D03*
X1503645Y749782D03*
X1509564Y1352564D03*
X1505070Y1358608D03*
X1517575Y741447D03*
X1584000Y749879D03*
X1582000Y756879D03*
X1590915Y758562D03*
X1582017Y900582D03*
X1602788Y758712D03*
X1594997Y758532D03*
X1606788Y758712D03*
X1618788D03*
X1610788D03*
X1614788D03*
X1622077Y1437033D03*
X1638928Y758712D03*
X1630928D03*
X1634928D03*
X1628600Y1428144D03*
X1653220Y615179D03*
X1654667Y759751D03*
X1662276Y540478D03*
X1658679Y759751D03*
X1666686D03*
X1662656D03*
X1658026Y1388743D03*
X1665117Y1428039D03*
X1665666Y1441298D03*
X1685686Y479170D03*
X1703000Y93379D03*
X1699000D03*
X1699150Y505569D03*
X1702848Y760585D03*
X1689565Y1388482D03*
X1710025Y18409D03*
X1713173Y31261D03*
X1708000Y93379D03*
X1708680Y172267D03*
X1707160Y204217D03*
X1710057Y695982D03*
X1709486Y711004D03*
X1714955Y760593D03*
X1710915D03*
X1706948Y760585D03*
X1769791Y31371D03*
X1758075Y40226D03*
X1755378Y228045D03*
X1779575Y13739D03*
X1774435Y13759D03*
G54D64*
X948474Y1645870D03*
X985286D03*
G54D28*
X109087Y522620D03*
X144640Y510230D03*
X338667Y772452D03*
X341527Y778362D03*
X358902Y773352D03*
X372117Y778576D03*
X381010Y734732D03*
X402700Y234167D03*
X420865Y215067D03*
X433695Y209862D03*
X426490Y244262D03*
X452071Y254862D03*
X461900Y215244D03*
X466300Y217803D03*
X461900Y222921D03*
X466300Y225480D03*
X461736Y301098D03*
X463198Y311587D03*
X470780Y1406980D03*
X486800Y259162D03*
X478500Y258862D03*
X474736Y302098D03*
X479736Y303598D03*
Y308598D03*
X472960Y602152D03*
X498700Y212685D03*
Y220362D03*
X503100Y215244D03*
Y222921D03*
X496028Y258590D03*
X495136Y300398D03*
X495036Y310398D03*
X508500Y232862D03*
X508502Y298813D03*
X508500Y303362D03*
X508136Y309398D03*
X536420Y309422D03*
X563482Y40826D03*
X558058Y46352D03*
X567865Y92656D03*
X570150Y102862D03*
X607630Y39662D03*
X606880Y44682D03*
X638281Y1254922D03*
X831705Y593877D03*
X859888Y593970D03*
X911340Y502872D03*
X912828Y498251D03*
X933012Y516711D03*
X970207Y1562731D03*
X1045760Y596272D03*
X1051680Y614772D03*
X1144810Y613762D03*
X1291306Y863361D03*
X1287674Y856290D03*
X1305288Y858104D03*
X1328187Y774757D03*
X1347640Y101950D03*
X1413900Y225212D03*
X1415340Y231812D03*
X1431430Y256383D03*
Y264060D03*
X1457361Y205982D03*
X1459961Y210432D03*
X1456150Y214382D03*
X1456770Y342942D03*
X1462790Y359042D03*
X1462870Y355012D03*
X1455920Y373941D03*
X1455642Y409646D03*
X1456777Y418596D03*
Y426546D03*
X1467761Y205982D03*
X1471308Y230640D03*
X1471690Y259862D03*
X1467700Y370953D03*
X1472758Y370817D03*
X1465836Y408668D03*
X1470942Y409718D03*
X1475250Y401812D03*
X1481766Y372288D03*
X1489443D03*
X1481766Y406238D03*
X1490384Y407292D03*
X1486880Y416863D03*
X1508959Y215802D03*
X1499922Y211240D03*
X1504484Y234562D03*
X1508410Y230842D03*
X1510017Y225516D03*
X1501840Y225502D03*
X1510810Y249742D03*
X1509040Y243362D03*
X1504890Y249862D03*
X1506600Y239092D03*
X1498184Y361723D03*
Y369798D03*
X1524539Y215551D03*
X1522009Y210825D03*
X1518110Y215551D03*
X1526998Y209645D03*
X1527732Y219488D03*
X1526152Y225114D03*
X1533385Y193108D03*
X1533148Y211614D03*
X1531824Y207677D03*
X1534194Y217519D03*
X1535561Y225393D03*
X1531110Y264862D03*
X1539150Y267132D03*
X1551160Y189342D03*
X1557900Y220362D03*
X1557760Y214792D03*
X1550353Y217352D03*
X1559400Y229832D03*
X1573560Y245078D03*
X1574760Y251032D03*
X1604240Y238242D03*
X1658450Y549550D03*
X1689093Y474538D03*
G54D46*
X450000Y278543D03*
X460000D03*
X470000D03*
X483500Y246362D03*
X480000Y278543D03*
X493500Y246362D03*
X490000Y278543D03*
X500000D03*
X510000D03*
X518563Y607067D03*
X508563D03*
X559236Y1441207D03*
X569236D03*
X688500Y1601900D03*
Y1611900D03*
X1041435Y143357D03*
Y153357D03*
X1056225Y143131D03*
Y153131D03*
X1099970Y1702570D03*
Y1712570D03*
X1689646Y115669D03*
X1679646D03*
X1689646Y125669D03*
Y135669D03*
X1679646Y125669D03*
Y135669D03*
X1689646Y145669D03*
Y155669D03*
X1679646Y145669D03*
Y155669D03*
X1689646Y165669D03*
X1679646D03*
X1689646Y175669D03*
X1771457Y1634646D03*
Y1644646D03*
G54D37*
X223948Y685639D03*
X230017Y582055D03*
Y616055D03*
Y650055D03*
X255213Y582055D03*
Y616055D03*
Y650055D03*
X249144Y685639D03*
X1047163Y253671D03*
X1072359D03*
X1605129Y602943D03*
X1598760Y638527D03*
Y672527D03*
Y706527D03*
X1623956Y638527D03*
Y672527D03*
Y706527D03*
X1630325Y602943D03*
G54D73*
X1297819Y250945D03*
X1297799Y258931D03*
X1293697Y254829D03*
X1293949Y262857D03*
X1289847Y258755D03*
X1301921Y255047D03*
G54D56*
X695101Y435336D03*
Y438486D03*
X685652Y476281D03*
Y479431D03*
X708300Y418750D03*
Y421900D03*
X701400Y435336D03*
Y438486D03*
X704550Y435336D03*
Y438486D03*
X698251Y435336D03*
Y438486D03*
X707699Y435336D03*
Y438486D03*
X710849Y435336D03*
Y438486D03*
X704550Y447935D03*
Y451085D03*
X701400Y447935D03*
Y451085D03*
X726597Y444785D03*
Y447935D03*
X723447Y476281D03*
Y479431D03*
G54D29*
X150927Y1237271D03*
Y1246719D03*
X268597Y1255061D03*
Y1264509D03*
X833207Y1239961D03*
Y1249409D03*
X1127069Y1237271D03*
Y1246719D03*
X1216149Y1239961D03*
Y1249409D03*
X1780500Y314299D03*
Y323747D03*
X1809349Y1236461D03*
Y1245909D03*
G54D38*
X277098Y185236D03*
X395208D03*
G54D74*
X1307199Y240916D03*
X1312149Y245866D03*
X1301906Y246041D03*
X1306856Y250991D03*
G54D47*
X473500Y246362D03*
X498563Y607067D03*
X520000Y278543D03*
X549236Y1441207D03*
X688500Y1621900D03*
X1041435Y163357D03*
X1056225Y163131D03*
X1099970Y1722570D03*
X1679646Y175669D03*
X1771457Y1624646D03*
G54D65*
X1010362Y1637176D03*
Y1663160D03*
X1036450Y1637260D03*
Y1663244D03*
G54D75*
X1343332Y175405D03*
G54D57*
X725073Y1241963D03*
X734521D03*
X1700586Y1235879D03*
X1710034D03*
G54D66*
X1041500Y382122D03*
Y389602D03*
G54D48*
X493384Y101473D03*
X491284D03*
X493384Y98373D03*
X491284D03*
X485480Y107972D03*
X487580D03*
X485480Y111282D03*
X487580D03*
X520480Y98012D03*
X518380D03*
X520480Y94882D03*
X518380D03*
X564888Y1316279D03*
X566988D03*
X1375626Y256280D03*
X1377726D03*
X1375626Y252680D03*
X1377726D03*
X1539927Y1324555D03*
X1542027D03*
G54D39*
X320561Y168009D03*
Y192509D03*
X366037Y1385515D03*
Y1410015D03*
X1338727Y1385105D03*
Y1409605D03*
G54D76*
X1340763Y173921D03*
G54D58*
X769895Y281705D03*
Y279146D03*
Y276587D03*
Y274028D03*
Y271469D03*
Y286823D03*
Y284264D03*
X764977Y298790D03*
Y296231D03*
Y311585D03*
Y309026D03*
Y306467D03*
Y303908D03*
Y301349D03*
X792895Y271469D03*
Y274028D03*
Y276587D03*
Y279146D03*
Y281705D03*
Y284264D03*
Y286823D03*
X787977Y296231D03*
Y298790D03*
Y301349D03*
Y303908D03*
Y306467D03*
Y309026D03*
Y311585D03*
X812499Y299070D03*
Y296511D03*
Y311865D03*
Y309306D03*
Y306747D03*
Y304188D03*
Y301629D03*
X822500Y281507D03*
Y278948D03*
Y276389D03*
Y273830D03*
Y271271D03*
Y286625D03*
Y284066D03*
X835499Y296511D03*
Y299070D03*
Y301629D03*
Y304188D03*
Y306747D03*
Y309306D03*
Y311865D03*
X845500Y271271D03*
Y273830D03*
Y276389D03*
Y278948D03*
Y281507D03*
Y284066D03*
Y286625D03*
G54D67*
X1156378Y133866D03*
G54D49*
X498487Y103452D03*
Y102074D03*
Y100696D03*
Y99318D03*
Y107586D03*
Y106208D03*
Y104830D03*
X508133Y99318D03*
Y100696D03*
Y102074D03*
Y103452D03*
Y104830D03*
Y106208D03*
Y107586D03*
G54D68*
X1164858Y592327D03*
Y589827D03*
Y607327D03*
Y604827D03*
Y602327D03*
Y599827D03*
Y597327D03*
Y594827D03*
X1186058Y592327D03*
Y589827D03*
Y607327D03*
Y604827D03*
Y602327D03*
Y599827D03*
Y597327D03*
Y594827D03*
G54D77*
X1339045Y207575D03*
G54D59*
X771724Y763455D03*
Y758337D03*
X778724D03*
Y760896D03*
Y763455D03*
G54D78*
X1360652Y231659D03*
X1362136Y233143D03*
X1363198Y229113D03*
X1364682Y230597D03*
G54D69*
X1200450Y1247609D03*
X1263543Y141412D03*
X1261848Y146363D03*
X1264183Y154756D03*
X1266983Y151686D03*
G54D79*
G01X-6350Y-464479D02*
Y-539479D01*
X493650D01*
Y-464479D01*
X-6350D01*
G01X5650Y-529479D02*
Y-534479D01*
G01X4193Y-529479D02*
X7107D01*
G01X12017Y-534479D02*
X9483D01*
Y-529479D01*
X12017D01*
G01X11003Y-531896D02*
X9483D01*
G01X14583Y-529479D02*
Y-534479D01*
X17117D01*
G01X20950Y-534646D02*
X20823Y-534562D01*
Y-534396D01*
X20950Y-534312D01*
X21077Y-534396D01*
Y-534562D01*
X20950Y-534646D01*
G01Y-532396D02*
X20823Y-532312D01*
Y-532146D01*
X20950Y-532062D01*
X21077Y-532146D01*
Y-532312D01*
X20950Y-532396D01*
G01X25733Y-536146D02*
X25100Y-535312D01*
X24783Y-534479D01*
Y-531146D01*
X25100Y-530312D01*
X25733Y-529479D01*
G01X31150D02*
X30643Y-529646D01*
X30263Y-530062D01*
X30010Y-530562D01*
X29820Y-531229D01*
X29757Y-531979D01*
X29820Y-532729D01*
X30010Y-533396D01*
X30263Y-533896D01*
X30643Y-534312D01*
X31150Y-534479D01*
X31657Y-534312D01*
X32037Y-533896D01*
X32290Y-533396D01*
X32480Y-532729D01*
X32543Y-531979D01*
X32480Y-531229D01*
X32290Y-530562D01*
X32037Y-530062D01*
X31657Y-529646D01*
X31150Y-529479D01*
G01X34857Y-533479D02*
X35237Y-534062D01*
X35743Y-534396D01*
X36313Y-534479D01*
X36820Y-534396D01*
X37327Y-533979D01*
X37643Y-533479D01*
X37707Y-532979D01*
X37580Y-532396D01*
X37137Y-531979D01*
X36693Y-531812D01*
X36123D01*
G01X36693D02*
X37073Y-531562D01*
X37390Y-531146D01*
X37517Y-530646D01*
X37390Y-530146D01*
X37073Y-529729D01*
X36503Y-529479D01*
X35933Y-529562D01*
X35363Y-529896D01*
G01X41667Y-536146D02*
X42300Y-535312D01*
X42617Y-534479D01*
Y-531146D01*
X42300Y-530312D01*
X41667Y-529479D01*
G01X45057Y-533479D02*
X45437Y-534062D01*
X45943Y-534396D01*
X46513Y-534479D01*
X47020Y-534396D01*
X47527Y-533979D01*
X47843Y-533479D01*
X47907Y-532979D01*
X47780Y-532396D01*
X47337Y-531979D01*
X46893Y-531812D01*
X46323D01*
G01X46893D02*
X47273Y-531562D01*
X47590Y-531146D01*
X47717Y-530646D01*
X47590Y-530146D01*
X47273Y-529729D01*
X46703Y-529479D01*
X46133Y-529562D01*
X45563Y-529896D01*
G01X50347Y-530312D02*
X50727Y-529812D01*
X51170Y-529562D01*
X51677Y-529479D01*
X52310Y-529646D01*
X52753Y-530062D01*
X52880Y-530562D01*
X52817Y-531062D01*
X52563Y-531479D01*
X51297Y-532312D01*
X50727Y-532896D01*
X50347Y-533729D01*
X50220Y-534479D01*
X52880D01*
G01X56523D02*
X56650Y-533396D01*
X56840Y-532479D01*
X57093Y-531646D01*
X57410Y-530729D01*
X57917Y-529479D01*
X55383D01*
G01X60927Y-532812D02*
X62573D01*
G01X65647Y-530312D02*
X66027Y-529812D01*
X66470Y-529562D01*
X66977Y-529479D01*
X67610Y-529646D01*
X68053Y-530062D01*
X68180Y-530562D01*
X68117Y-531062D01*
X67863Y-531479D01*
X66597Y-532312D01*
X66027Y-532896D01*
X65647Y-533729D01*
X65520Y-534479D01*
X68180D01*
G01X70557Y-533479D02*
X70937Y-534062D01*
X71443Y-534396D01*
X72013Y-534479D01*
X72520Y-534396D01*
X73027Y-533979D01*
X73343Y-533479D01*
X73407Y-532979D01*
X73280Y-532396D01*
X72837Y-531979D01*
X72393Y-531812D01*
X71823D01*
G01X72393D02*
X72773Y-531562D01*
X73090Y-531146D01*
X73217Y-530646D01*
X73090Y-530146D01*
X72773Y-529729D01*
X72203Y-529479D01*
X71633Y-529562D01*
X71063Y-529896D01*
G01X77810Y-534479D02*
Y-529479D01*
X75467Y-533062D01*
X78633D01*
G01X80757Y-533729D02*
X81137Y-534146D01*
X81580Y-534396D01*
X82150Y-534479D01*
X82720Y-534312D01*
X83163Y-533979D01*
X83480Y-533396D01*
X83543Y-532729D01*
X83417Y-532062D01*
X83100Y-531646D01*
X82657Y-531312D01*
X82213Y-531229D01*
X81770Y-531312D01*
X81200Y-531646D01*
X81390Y-529479D01*
X83100D01*
G01X91147Y-534479D02*
Y-529479D01*
X93553D01*
G01X92667Y-531896D02*
X91147D01*
G01X95867Y-534479D02*
X97450Y-529479D01*
X99033Y-534479D01*
G01X98463Y-532729D02*
X96437D01*
G01X101220Y-534479D02*
X103880Y-529479D01*
G01X101220D02*
X103880Y-534479D01*
G01X107650Y-534646D02*
X107523Y-534562D01*
Y-534396D01*
X107650Y-534312D01*
X107777Y-534396D01*
Y-534562D01*
X107650Y-534646D01*
G01Y-532396D02*
X107523Y-532312D01*
Y-532146D01*
X107650Y-532062D01*
X107777Y-532146D01*
Y-532312D01*
X107650Y-532396D01*
G01X112433Y-536146D02*
X111800Y-535312D01*
X111483Y-534479D01*
Y-531146D01*
X111800Y-530312D01*
X112433Y-529479D01*
G01X117850D02*
X117343Y-529646D01*
X116963Y-530062D01*
X116710Y-530562D01*
X116520Y-531229D01*
X116457Y-531979D01*
X116520Y-532729D01*
X116710Y-533396D01*
X116963Y-533896D01*
X117343Y-534312D01*
X117850Y-534479D01*
X118357Y-534312D01*
X118737Y-533896D01*
X118990Y-533396D01*
X119180Y-532729D01*
X119243Y-531979D01*
X119180Y-531229D01*
X118990Y-530562D01*
X118737Y-530062D01*
X118357Y-529646D01*
X117850Y-529479D01*
G01X121557Y-533479D02*
X121937Y-534062D01*
X122443Y-534396D01*
X123013Y-534479D01*
X123520Y-534396D01*
X124027Y-533979D01*
X124343Y-533479D01*
X124407Y-532979D01*
X124280Y-532396D01*
X123837Y-531979D01*
X123393Y-531812D01*
X122823D01*
G01X123393D02*
X123773Y-531562D01*
X124090Y-531146D01*
X124217Y-530646D01*
X124090Y-530146D01*
X123773Y-529729D01*
X123203Y-529479D01*
X122633Y-529562D01*
X122063Y-529896D01*
G01X128367Y-536146D02*
X129000Y-535312D01*
X129317Y-534479D01*
Y-531146D01*
X129000Y-530312D01*
X128367Y-529479D01*
G01X131757Y-533479D02*
X132137Y-534062D01*
X132643Y-534396D01*
X133213Y-534479D01*
X133720Y-534396D01*
X134227Y-533979D01*
X134543Y-533479D01*
X134607Y-532979D01*
X134480Y-532396D01*
X134037Y-531979D01*
X133593Y-531812D01*
X133023D01*
G01X133593D02*
X133973Y-531562D01*
X134290Y-531146D01*
X134417Y-530646D01*
X134290Y-530146D01*
X133973Y-529729D01*
X133403Y-529479D01*
X132833Y-529562D01*
X132263Y-529896D01*
G01X137173Y-533896D02*
X137617Y-534312D01*
X138123Y-534479D01*
X138630Y-534312D01*
X139073Y-533812D01*
X139390Y-533062D01*
X139517Y-532312D01*
Y-531396D01*
X139390Y-530646D01*
X139073Y-529979D01*
X138693Y-529646D01*
X138250Y-529479D01*
X137743Y-529646D01*
X137363Y-529979D01*
X137110Y-530479D01*
X136983Y-531146D01*
X137110Y-531729D01*
X137427Y-532312D01*
X137807Y-532646D01*
X138250Y-532729D01*
X138757Y-532562D01*
X139137Y-532146D01*
X139517Y-531396D01*
G01X143223Y-534479D02*
X143350Y-533396D01*
X143540Y-532479D01*
X143793Y-531646D01*
X144110Y-530729D01*
X144617Y-529479D01*
X142083D01*
G01X147627Y-532812D02*
X149273D01*
G01X152157Y-533479D02*
X152537Y-534062D01*
X153043Y-534396D01*
X153613Y-534479D01*
X154120Y-534396D01*
X154627Y-533979D01*
X154943Y-533479D01*
X155007Y-532979D01*
X154880Y-532396D01*
X154437Y-531979D01*
X153993Y-531812D01*
X153423D01*
G01X153993D02*
X154373Y-531562D01*
X154690Y-531146D01*
X154817Y-530646D01*
X154690Y-530146D01*
X154373Y-529729D01*
X153803Y-529479D01*
X153233Y-529562D01*
X152663Y-529896D01*
G01X157447Y-532396D02*
X157890Y-531812D01*
X158270Y-531479D01*
X158777Y-531312D01*
X159220Y-531479D01*
X159537Y-531812D01*
X159790Y-532312D01*
X159853Y-532896D01*
X159790Y-533396D01*
X159537Y-533896D01*
X159157Y-534312D01*
X158713Y-534479D01*
X158207Y-534312D01*
X157763Y-533812D01*
X157510Y-533062D01*
X157447Y-532229D01*
X157573Y-531146D01*
X157763Y-530562D01*
X158080Y-529979D01*
X158523Y-529562D01*
X158967Y-529479D01*
X159410Y-529646D01*
X159727Y-530062D01*
G01X163750Y-534479D02*
Y-529479D01*
X162990Y-530479D01*
G01Y-534479D02*
X164510D01*
G01X169610D02*
Y-529479D01*
X167267Y-533062D01*
X170433D01*
G01X188650Y-464479D02*
Y-539479D01*
G01Y-514479D02*
X291650D01*
Y-489479D01*
G01X188650D02*
X291650D01*
G01Y-464479D02*
Y-539479D01*
G01X293650Y-464479D02*
Y-539479D01*
G01X299157Y-524479D02*
Y-519479D01*
X300423D01*
X300930Y-519729D01*
X301310Y-520062D01*
X301627Y-520562D01*
X301880Y-521146D01*
X301943Y-521979D01*
X301880Y-522812D01*
X301627Y-523396D01*
X301310Y-523896D01*
X300930Y-524229D01*
X300423Y-524479D01*
X299157D01*
G01X304067D02*
X305650Y-519479D01*
X307233Y-524479D01*
G01X306663Y-522729D02*
X304637D01*
G01X310750Y-519479D02*
Y-524479D01*
G01X309293Y-519479D02*
X312207D01*
G01X317117Y-524479D02*
X314583D01*
Y-519479D01*
X317117D01*
G01X316103Y-521896D02*
X314583D01*
G01X320950Y-524646D02*
X320823Y-524562D01*
Y-524396D01*
X320950Y-524312D01*
X321077Y-524396D01*
Y-524562D01*
X320950Y-524646D01*
G01Y-522396D02*
X320823Y-522312D01*
Y-522146D01*
X320950Y-522062D01*
X321077Y-522146D01*
Y-522312D01*
X320950Y-522396D01*
G01X299283Y-499479D02*
Y-494479D01*
X300803D01*
X301310Y-494729D01*
X301690Y-495312D01*
X301817Y-495979D01*
X301690Y-496646D01*
X301373Y-497146D01*
X300803Y-497396D01*
X299283D01*
G01X304510Y-499646D02*
X306790Y-494479D01*
G01X309293Y-499479D02*
Y-494479D01*
X312207Y-499479D01*
Y-494479D01*
G01X315850Y-499646D02*
X315723Y-499562D01*
Y-499396D01*
X315850Y-499312D01*
X315977Y-499396D01*
Y-499562D01*
X315850Y-499646D01*
G01Y-497396D02*
X315723Y-497312D01*
Y-497146D01*
X315850Y-497062D01*
X315977Y-497146D01*
Y-497312D01*
X315850Y-497396D01*
G01X293650Y-514479D02*
X493650D01*
G01X293650Y-489479D02*
X493650D01*
G01X299283Y-474479D02*
Y-469479D01*
X300803D01*
X301310Y-469729D01*
X301690Y-470312D01*
X301817Y-470979D01*
X301690Y-471646D01*
X301373Y-472146D01*
X300803Y-472396D01*
X299283D01*
G01X304383Y-474479D02*
Y-469479D01*
X305967D01*
X306473Y-469729D01*
X306790Y-470062D01*
X306917Y-470729D01*
X306790Y-471396D01*
X306410Y-471812D01*
X305967Y-472062D01*
X304383D01*
G01X305967D02*
X306917Y-474479D01*
G01X310750D02*
X310243Y-474396D01*
X309800Y-474062D01*
X309420Y-473562D01*
X309167Y-472979D01*
X309040Y-472312D01*
Y-471646D01*
X309167Y-470979D01*
X309420Y-470396D01*
X309800Y-469896D01*
X310243Y-469562D01*
X310750Y-469479D01*
X311257Y-469562D01*
X311700Y-469896D01*
X312080Y-470396D01*
X312333Y-470979D01*
X312460Y-471646D01*
Y-472312D01*
X312333Y-472979D01*
X312080Y-473562D01*
X311700Y-474062D01*
X311257Y-474396D01*
X310750Y-474479D01*
G01X314583Y-473479D02*
X314900Y-473979D01*
X315280Y-474312D01*
X315723Y-474479D01*
X316230Y-474312D01*
X316610Y-473979D01*
X316990Y-473479D01*
X317117Y-472812D01*
Y-469479D01*
G01X322217Y-474479D02*
X319683D01*
Y-469479D01*
X322217D01*
G01X321203Y-471896D02*
X319683D01*
G01X327443Y-469896D02*
X327063Y-469646D01*
X326620Y-469479D01*
X326113D01*
X325543Y-469729D01*
X325100Y-470146D01*
X324783Y-470646D01*
X324530Y-471479D01*
X324467Y-472229D01*
X324593Y-472979D01*
X324783Y-473479D01*
X325163Y-473979D01*
X325607Y-474312D01*
X326050Y-474479D01*
X326493D01*
X326937Y-474312D01*
X327317Y-474062D01*
X327633Y-473729D01*
G01X331150Y-469479D02*
Y-474479D01*
G01X329693Y-469479D02*
X332607D01*
G01X336250Y-474646D02*
X336123Y-474562D01*
Y-474396D01*
X336250Y-474312D01*
X336377Y-474396D01*
Y-474562D01*
X336250Y-474646D01*
G01Y-472396D02*
X336123Y-472312D01*
Y-472146D01*
X336250Y-472062D01*
X336377Y-472146D01*
Y-472312D01*
X336250Y-472396D01*
G01X408650Y-514479D02*
Y-539479D01*
G01X411283Y-516979D02*
Y-521979D01*
X413817D01*
G01X416890Y-516979D02*
X418410D01*
G01X417650D02*
Y-521979D01*
G01X416890D02*
X418410D01*
G01X423257Y-519312D02*
X423510Y-519062D01*
X423700Y-518646D01*
X423827Y-518062D01*
X423700Y-517562D01*
X423447Y-517229D01*
X423003Y-516979D01*
X421293D01*
Y-521979D01*
X423383D01*
X423827Y-521646D01*
X424080Y-521146D01*
X424207Y-520562D01*
X424080Y-519979D01*
X423700Y-519479D01*
X423257Y-519312D01*
X421293D01*
G01X427850Y-522146D02*
X427723Y-522062D01*
Y-521896D01*
X427850Y-521812D01*
X427977Y-521896D01*
Y-522062D01*
X427850Y-522146D01*
G01Y-519896D02*
X427723Y-519812D01*
Y-519646D01*
X427850Y-519562D01*
X427977Y-519646D01*
Y-519812D01*
X427850Y-519896D01*
G01X451650Y-514479D02*
Y-539479D01*
G01Y-489479D02*
Y-514479D01*
G01X456663Y-541646D02*
X456770Y-541521D01*
X456850Y-541312D01*
X456903Y-541021D01*
X456850Y-540771D01*
X456743Y-540604D01*
X456557Y-540479D01*
X455837D01*
Y-542979D01*
X456717D01*
X456903Y-542812D01*
X457010Y-542562D01*
X457063Y-542271D01*
X457010Y-541979D01*
X456850Y-541729D01*
X456663Y-541646D01*
X455837D01*
G01X459130Y-542979D02*
Y-541312D01*
G01Y-541604D02*
X459023Y-541437D01*
X458863Y-541354D01*
X458677Y-541312D01*
X458490Y-541396D01*
X458330Y-541562D01*
X458223Y-541812D01*
X458170Y-542146D01*
X458223Y-542479D01*
X458330Y-542729D01*
X458490Y-542896D01*
X458677Y-542979D01*
X458863Y-542937D01*
X459023Y-542812D01*
X459130Y-542646D01*
G01X460450Y-542687D02*
X460583Y-542854D01*
X460770Y-542979D01*
X460930D01*
X461090Y-542896D01*
X461197Y-542771D01*
X461250Y-542604D01*
X461223Y-542354D01*
X461117Y-542229D01*
X460637Y-541979D01*
X460530Y-541687D01*
X460583Y-541479D01*
X460690Y-541354D01*
X460850Y-541312D01*
X461010Y-541354D01*
X461170Y-541479D01*
G01X462650Y-541854D02*
X463503D01*
X463423Y-541562D01*
X463290Y-541396D01*
X463103Y-541312D01*
X462917Y-541354D01*
X462757Y-541479D01*
X462650Y-541771D01*
X462597Y-542021D01*
Y-542271D01*
X462650Y-542521D01*
X462783Y-542771D01*
X462943Y-542937D01*
X463130Y-542979D01*
X463317Y-542896D01*
X463503Y-542646D01*
G01X464770Y-542979D02*
Y-540479D01*
G01Y-541729D02*
X464903Y-541479D01*
X465063Y-541354D01*
X465223Y-541312D01*
X465463Y-541396D01*
X465623Y-541562D01*
X465730Y-541854D01*
Y-542187D01*
X465677Y-542521D01*
X465570Y-542771D01*
X465383Y-542937D01*
X465223Y-542979D01*
X465063Y-542937D01*
X464903Y-542812D01*
X464770Y-542604D01*
G01X467450Y-542979D02*
X467290Y-542937D01*
X467130Y-542771D01*
X467023Y-542479D01*
X466970Y-542146D01*
X467023Y-541812D01*
X467130Y-541521D01*
X467290Y-541354D01*
X467450Y-541312D01*
X467610Y-541354D01*
X467770Y-541521D01*
X467877Y-541812D01*
X467903Y-542146D01*
X467877Y-542479D01*
X467770Y-542771D01*
X467610Y-542937D01*
X467450Y-542979D01*
G01X470130D02*
Y-541312D01*
G01Y-541604D02*
X470023Y-541437D01*
X469863Y-541354D01*
X469677Y-541312D01*
X469490Y-541396D01*
X469330Y-541562D01*
X469223Y-541812D01*
X469170Y-542146D01*
X469223Y-542479D01*
X469330Y-542729D01*
X469490Y-542896D01*
X469677Y-542979D01*
X469863Y-542937D01*
X470023Y-542812D01*
X470130Y-542646D01*
G01X471477Y-542979D02*
Y-541312D01*
G01Y-541646D02*
X471610Y-541479D01*
X471743Y-541354D01*
X471930Y-541312D01*
X472063Y-541354D01*
X472223Y-541479D01*
G01X474530Y-540479D02*
Y-542979D01*
G01Y-542604D02*
X474423Y-542812D01*
X474263Y-542937D01*
X474077Y-542979D01*
X473863Y-542896D01*
X473703Y-542687D01*
X473597Y-542437D01*
X473570Y-542146D01*
X473597Y-541854D01*
X473703Y-541604D01*
X473863Y-541396D01*
X474077Y-541312D01*
X474263Y-541354D01*
X474397Y-541437D01*
X474530Y-541604D01*
G01X477917Y-542979D02*
Y-540479D01*
X478583D01*
X478797Y-540604D01*
X478930Y-540771D01*
X478983Y-541104D01*
X478930Y-541437D01*
X478770Y-541646D01*
X478583Y-541771D01*
X477917D01*
G01X478583D02*
X478983Y-542979D01*
G01X480250Y-541854D02*
X481103D01*
X481023Y-541562D01*
X480890Y-541396D01*
X480703Y-541312D01*
X480517Y-541354D01*
X480357Y-541479D01*
X480250Y-541771D01*
X480197Y-542021D01*
Y-542271D01*
X480250Y-542521D01*
X480383Y-542771D01*
X480543Y-542937D01*
X480730Y-542979D01*
X480917Y-542896D01*
X481103Y-542646D01*
G01X482370Y-541312D02*
X482850Y-542979D01*
X483330Y-541312D01*
G01X485050Y-543062D02*
X484997Y-543021D01*
Y-542937D01*
X485050Y-542896D01*
X485103Y-542937D01*
Y-543021D01*
X485050Y-543062D01*
G01X487250Y-542979D02*
X487437Y-542937D01*
X487650Y-542812D01*
X487783Y-542604D01*
X487837Y-542312D01*
X487783Y-542021D01*
X487623Y-541771D01*
X487383Y-541646D01*
X487117D01*
X486957Y-541562D01*
X486823Y-541354D01*
X486770Y-541062D01*
X486850Y-540771D01*
X487037Y-540562D01*
X487250Y-540479D01*
X487463Y-540562D01*
X487650Y-540771D01*
X487730Y-541062D01*
X487677Y-541354D01*
X487543Y-541562D01*
X487383Y-541646D01*
X487117D01*
X486877Y-541771D01*
X486717Y-542021D01*
X486663Y-542312D01*
X486717Y-542604D01*
X486850Y-542812D01*
X487063Y-542937D01*
X487250Y-542979D01*
G01X489663Y-541646D02*
X489770Y-541521D01*
X489850Y-541312D01*
X489903Y-541021D01*
X489850Y-540771D01*
X489743Y-540604D01*
X489557Y-540479D01*
X488837D01*
Y-542979D01*
X489717D01*
X489903Y-542812D01*
X490010Y-542562D01*
X490063Y-542271D01*
X490010Y-541979D01*
X489850Y-541729D01*
X489663Y-541646D01*
X488837D01*
G01X455550Y-516979D02*
Y-521979D01*
G01X454093Y-516979D02*
X457007D01*
G01X460650Y-521979D02*
X460270Y-521896D01*
X459890Y-521562D01*
X459637Y-520979D01*
X459510Y-520312D01*
X459637Y-519646D01*
X459890Y-519062D01*
X460270Y-518729D01*
X460650Y-518646D01*
X461030Y-518729D01*
X461410Y-519062D01*
X461663Y-519646D01*
X461727Y-520312D01*
X461663Y-520979D01*
X461410Y-521562D01*
X461030Y-521896D01*
X460650Y-521979D01*
G01X465750D02*
X465370Y-521896D01*
X464990Y-521562D01*
X464737Y-520979D01*
X464610Y-520312D01*
X464737Y-519646D01*
X464990Y-519062D01*
X465370Y-518729D01*
X465750Y-518646D01*
X466130Y-518729D01*
X466510Y-519062D01*
X466763Y-519646D01*
X466827Y-520312D01*
X466763Y-520979D01*
X466510Y-521562D01*
X466130Y-521896D01*
X465750Y-521979D01*
G01X470850D02*
Y-516979D01*
G01X475950Y-522146D02*
X475823Y-522062D01*
Y-521896D01*
X475950Y-521812D01*
X476077Y-521896D01*
Y-522062D01*
X475950Y-522146D01*
G01Y-519896D02*
X475823Y-519812D01*
Y-519646D01*
X475950Y-519562D01*
X476077Y-519646D01*
Y-519812D01*
X475950Y-519896D01*
G01X454283Y-496979D02*
Y-491979D01*
X455867D01*
X456373Y-492229D01*
X456690Y-492562D01*
X456817Y-493229D01*
X456690Y-493896D01*
X456310Y-494312D01*
X455867Y-494562D01*
X454283D01*
G01X455867D02*
X456817Y-496979D01*
G01X461917D02*
X459383D01*
Y-491979D01*
X461917D01*
G01X460903Y-494396D02*
X459383D01*
G01X464167Y-491979D02*
X465750Y-496979D01*
X467333Y-491979D01*
G01X470850Y-497146D02*
X470723Y-497062D01*
Y-496896D01*
X470850Y-496812D01*
X470977Y-496896D01*
Y-497062D01*
X470850Y-497146D01*
G01Y-494896D02*
X470723Y-494812D01*
Y-494646D01*
X470850Y-494562D01*
X470977Y-494646D01*
Y-494812D01*
X470850Y-494896D01*
G01X-984580Y-698988D02*
Y4193602D01*
X5868320D01*
Y-698988D01*
X-984580D01*
G01X7723Y-521204D02*
X7253Y-520889D01*
X6705Y-520679D01*
X6078D01*
X5373Y-520994D01*
X4825Y-521519D01*
X4433Y-522149D01*
X4120Y-523199D01*
X4042Y-524144D01*
X4198Y-525089D01*
X4433Y-525719D01*
X4903Y-526349D01*
X5452Y-526769D01*
X6000Y-526979D01*
X6548D01*
X7097Y-526769D01*
X7567Y-526454D01*
X7958Y-526034D01*
G01X11360Y-520679D02*
X13240D01*
G01X12300D02*
Y-526979D01*
G01X11360D02*
X13240D01*
G01X18600Y-520679D02*
Y-526979D01*
G01X16798Y-520679D02*
X20402D01*
G01X24900Y-526979D02*
Y-524144D01*
X23333Y-520679D01*
G01X26467D02*
X24900Y-524144D01*
G01X35777Y-525719D02*
X36247Y-526454D01*
X36873Y-526874D01*
X37578Y-526979D01*
X38205Y-526874D01*
X38832Y-526349D01*
X39223Y-525719D01*
X39302Y-525089D01*
X39145Y-524354D01*
X38597Y-523829D01*
X38048Y-523619D01*
X37343D01*
G01X38048D02*
X38518Y-523304D01*
X38910Y-522779D01*
X39067Y-522149D01*
X38910Y-521519D01*
X38518Y-520994D01*
X37813Y-520679D01*
X37108Y-520784D01*
X36403Y-521204D01*
G01X42077Y-525719D02*
X42547Y-526454D01*
X43173Y-526874D01*
X43878Y-526979D01*
X44505Y-526874D01*
X45132Y-526349D01*
X45523Y-525719D01*
X45602Y-525089D01*
X45445Y-524354D01*
X44897Y-523829D01*
X44348Y-523619D01*
X43643D01*
G01X44348D02*
X44818Y-523304D01*
X45210Y-522779D01*
X45367Y-522149D01*
X45210Y-521519D01*
X44818Y-520994D01*
X44113Y-520679D01*
X43408Y-520784D01*
X42703Y-521204D01*
G01X48377Y-525719D02*
X48847Y-526454D01*
X49473Y-526874D01*
X50178Y-526979D01*
X50805Y-526874D01*
X51432Y-526349D01*
X51823Y-525719D01*
X51902Y-525089D01*
X51745Y-524354D01*
X51197Y-523829D01*
X50648Y-523619D01*
X49943D01*
G01X50648D02*
X51118Y-523304D01*
X51510Y-522779D01*
X51667Y-522149D01*
X51510Y-521519D01*
X51118Y-520994D01*
X50413Y-520679D01*
X49708Y-520784D01*
X49003Y-521204D01*
G01X56243Y-526979D02*
X56400Y-525614D01*
X56635Y-524459D01*
X56948Y-523409D01*
X57340Y-522254D01*
X57967Y-520679D01*
X54833D01*
G01X62543Y-526979D02*
X62700Y-525614D01*
X62935Y-524459D01*
X63248Y-523409D01*
X63640Y-522254D01*
X64267Y-520679D01*
X61133D01*
G01X68843Y-528134D02*
X69157Y-526769D01*
G01X75300Y-520679D02*
Y-526979D01*
G01X73498Y-520679D02*
X77102D01*
G01X79642Y-526979D02*
X81600Y-520679D01*
X83558Y-526979D01*
G01X82853Y-524774D02*
X80347D01*
G01X86960Y-520679D02*
X88840D01*
G01X87900D02*
Y-526979D01*
G01X86960D02*
X88840D01*
G01X91850Y-520679D02*
X92947Y-526979D01*
X94200Y-520679D01*
X95453Y-526979D01*
X96550Y-520679D01*
G01X98542Y-526979D02*
X100500Y-520679D01*
X102458Y-526979D01*
G01X101753Y-524774D02*
X99247D01*
G01X104998Y-526979D02*
Y-520679D01*
X108602Y-526979D01*
Y-520679D01*
G01X119008Y-529079D02*
X118225Y-528029D01*
X117833Y-526979D01*
Y-522779D01*
X118225Y-521729D01*
X119008Y-520679D01*
G01X130433Y-526979D02*
Y-520679D01*
X132392D01*
X133018Y-520994D01*
X133410Y-521414D01*
X133567Y-522254D01*
X133410Y-523094D01*
X132940Y-523619D01*
X132392Y-523934D01*
X130433D01*
G01X132392D02*
X133567Y-526979D01*
G01X138300Y-527189D02*
X138143Y-527084D01*
Y-526874D01*
X138300Y-526769D01*
X138457Y-526874D01*
Y-527084D01*
X138300Y-527189D01*
G01X144600Y-526979D02*
X143973Y-526874D01*
X143425Y-526454D01*
X142955Y-525824D01*
X142642Y-525089D01*
X142485Y-524249D01*
Y-523409D01*
X142642Y-522569D01*
X142955Y-521834D01*
X143425Y-521204D01*
X143973Y-520784D01*
X144600Y-520679D01*
X145227Y-520784D01*
X145775Y-521204D01*
X146245Y-521834D01*
X146558Y-522569D01*
X146715Y-523409D01*
Y-524249D01*
X146558Y-525089D01*
X146245Y-525824D01*
X145775Y-526454D01*
X145227Y-526874D01*
X144600Y-526979D01*
G01X150900Y-527189D02*
X150743Y-527084D01*
Y-526874D01*
X150900Y-526769D01*
X151057Y-526874D01*
Y-527084D01*
X150900Y-527189D01*
G01X158923Y-521204D02*
X158453Y-520889D01*
X157905Y-520679D01*
X157278D01*
X156573Y-520994D01*
X156025Y-521519D01*
X155633Y-522149D01*
X155320Y-523199D01*
X155242Y-524144D01*
X155398Y-525089D01*
X155633Y-525719D01*
X156103Y-526349D01*
X156652Y-526769D01*
X157200Y-526979D01*
X157748D01*
X158297Y-526769D01*
X158767Y-526454D01*
X159158Y-526034D01*
G01X163500Y-527189D02*
X163343Y-527084D01*
Y-526874D01*
X163500Y-526769D01*
X163657Y-526874D01*
Y-527084D01*
X163500Y-527189D01*
G01X170192Y-529079D02*
X170975Y-528029D01*
X171367Y-526979D01*
Y-522779D01*
X170975Y-521729D01*
X170192Y-520679D01*
G01X6470Y-513829D02*
X8037D01*
Y-515719D01*
X7567Y-516349D01*
X7018Y-516769D01*
X6235Y-516979D01*
X5452Y-516769D01*
X4903Y-516349D01*
X4433Y-515719D01*
X4120Y-514984D01*
X3963Y-514144D01*
Y-513409D01*
X4120Y-512779D01*
X4433Y-512044D01*
X4903Y-511414D01*
X5373Y-510994D01*
X6000Y-510679D01*
X6548D01*
X7175Y-510889D01*
X7645Y-511309D01*
G01X10577Y-510679D02*
Y-515194D01*
X10890Y-516139D01*
X11517Y-516769D01*
X12300Y-516979D01*
X13083Y-516769D01*
X13710Y-516139D01*
X14023Y-515194D01*
Y-510679D01*
G01X17660D02*
X19540D01*
G01X18600D02*
Y-516979D01*
G01X17660D02*
X19540D01*
G01X23255Y-516139D02*
X23882Y-516664D01*
X24587Y-516979D01*
X25213D01*
X25840Y-516664D01*
X26310Y-516139D01*
X26545Y-515404D01*
X26388Y-514669D01*
X25997Y-514039D01*
X25292Y-513619D01*
X24352Y-513409D01*
X23803Y-512989D01*
X23568Y-512254D01*
X23725Y-511519D01*
X24117Y-510994D01*
X24665Y-510679D01*
X25213D01*
X25762Y-510889D01*
X26232Y-511414D01*
G01X29555Y-516979D02*
Y-510679D01*
G01X32845D02*
Y-516979D01*
G01Y-513829D02*
X29555D01*
G01X35542Y-516979D02*
X37500Y-510679D01*
X39458Y-516979D01*
G01X38753Y-514774D02*
X36247D01*
G01X41998Y-516979D02*
Y-510679D01*
X45602Y-516979D01*
Y-510679D01*
G01X54677Y-516979D02*
Y-510679D01*
X56243D01*
X56870Y-510994D01*
X57340Y-511414D01*
X57732Y-512044D01*
X58045Y-512779D01*
X58123Y-513829D01*
X58045Y-514879D01*
X57732Y-515614D01*
X57340Y-516244D01*
X56870Y-516664D01*
X56243Y-516979D01*
X54677D01*
G01X61760Y-510679D02*
X63640D01*
G01X62700D02*
Y-516979D01*
G01X61760D02*
X63640D01*
G01X67355Y-516139D02*
X67982Y-516664D01*
X68687Y-516979D01*
X69313D01*
X69940Y-516664D01*
X70410Y-516139D01*
X70645Y-515404D01*
X70488Y-514669D01*
X70097Y-514039D01*
X69392Y-513619D01*
X68452Y-513409D01*
X67903Y-512989D01*
X67668Y-512254D01*
X67825Y-511519D01*
X68217Y-510994D01*
X68765Y-510679D01*
X69313D01*
X69862Y-510889D01*
X70332Y-511414D01*
G01X75300Y-510679D02*
Y-516979D01*
G01X73498Y-510679D02*
X77102D01*
G01X81600Y-517189D02*
X81443Y-517084D01*
Y-516874D01*
X81600Y-516769D01*
X81757Y-516874D01*
Y-517084D01*
X81600Y-517189D01*
G01X87743Y-518134D02*
X88057Y-516769D01*
G01X94200Y-510679D02*
Y-516979D01*
G01X92398Y-510679D02*
X96002D01*
G01X98542Y-516979D02*
X100500Y-510679D01*
X102458Y-516979D01*
G01X101753Y-514774D02*
X99247D01*
G01X106800Y-516979D02*
X106173Y-516874D01*
X105625Y-516454D01*
X105155Y-515824D01*
X104842Y-515089D01*
X104685Y-514249D01*
Y-513409D01*
X104842Y-512569D01*
X105155Y-511834D01*
X105625Y-511204D01*
X106173Y-510784D01*
X106800Y-510679D01*
X107427Y-510784D01*
X107975Y-511204D01*
X108445Y-511834D01*
X108758Y-512569D01*
X108915Y-513409D01*
Y-514249D01*
X108758Y-515089D01*
X108445Y-515824D01*
X107975Y-516454D01*
X107427Y-516874D01*
X106800Y-516979D01*
G01X113100D02*
Y-514144D01*
X111533Y-510679D01*
G01X114667D02*
X113100Y-514144D01*
G01X117677Y-510679D02*
Y-515194D01*
X117990Y-516139D01*
X118617Y-516769D01*
X119400Y-516979D01*
X120183Y-516769D01*
X120810Y-516139D01*
X121123Y-515194D01*
Y-510679D01*
G01X123742Y-516979D02*
X125700Y-510679D01*
X127658Y-516979D01*
G01X126953Y-514774D02*
X124447D01*
G01X130198Y-516979D02*
Y-510679D01*
X133802Y-516979D01*
Y-510679D01*
G01X4198Y-506979D02*
Y-500679D01*
X7802Y-506979D01*
Y-500679D01*
G01X12300Y-506979D02*
X11673Y-506874D01*
X11125Y-506454D01*
X10655Y-505824D01*
X10342Y-505089D01*
X10185Y-504249D01*
Y-503409D01*
X10342Y-502569D01*
X10655Y-501834D01*
X11125Y-501204D01*
X11673Y-500784D01*
X12300Y-500679D01*
X12927Y-500784D01*
X13475Y-501204D01*
X13945Y-501834D01*
X14258Y-502569D01*
X14415Y-503409D01*
Y-504249D01*
X14258Y-505089D01*
X13945Y-505824D01*
X13475Y-506454D01*
X12927Y-506874D01*
X12300Y-506979D01*
G01X18600Y-507189D02*
X18443Y-507084D01*
Y-506874D01*
X18600Y-506769D01*
X18757Y-506874D01*
Y-507084D01*
X18600Y-507189D01*
G01X23412Y-501729D02*
X23882Y-501099D01*
X24430Y-500784D01*
X25057Y-500679D01*
X25840Y-500889D01*
X26388Y-501414D01*
X26545Y-502044D01*
X26467Y-502674D01*
X26153Y-503199D01*
X24587Y-504249D01*
X23882Y-504984D01*
X23412Y-506034D01*
X23255Y-506979D01*
X26545D01*
G01X31200D02*
Y-500679D01*
X30260Y-501939D01*
G01Y-506979D02*
X32140D01*
G01X37500D02*
Y-500679D01*
X36560Y-501939D01*
G01Y-506979D02*
X38440D01*
G01X43643Y-508134D02*
X43957Y-506769D01*
G01X47750Y-500679D02*
X48847Y-506979D01*
X50100Y-500679D01*
X51353Y-506979D01*
X52450Y-500679D01*
G01X57967Y-506979D02*
X54833D01*
Y-500679D01*
X57967D01*
G01X56713Y-503724D02*
X54833D01*
G01X60898Y-506979D02*
Y-500679D01*
X64502Y-506979D01*
Y-500679D01*
G01X67355Y-506979D02*
Y-500679D01*
G01X70645D02*
Y-506979D01*
G01Y-503829D02*
X67355D01*
G01X73577Y-500679D02*
Y-505194D01*
X73890Y-506139D01*
X74517Y-506769D01*
X75300Y-506979D01*
X76083Y-506769D01*
X76710Y-506139D01*
X77023Y-505194D01*
Y-500679D01*
G01X79642Y-506979D02*
X81600Y-500679D01*
X83558Y-506979D01*
G01X82853Y-504774D02*
X80347D01*
G01X92712Y-501729D02*
X93182Y-501099D01*
X93730Y-500784D01*
X94357Y-500679D01*
X95140Y-500889D01*
X95688Y-501414D01*
X95845Y-502044D01*
X95767Y-502674D01*
X95453Y-503199D01*
X93887Y-504249D01*
X93182Y-504984D01*
X92712Y-506034D01*
X92555Y-506979D01*
X95845D01*
G01X98698D02*
Y-500679D01*
X102302Y-506979D01*
Y-500679D01*
G01X105077Y-506979D02*
Y-500679D01*
X106643D01*
X107270Y-500994D01*
X107740Y-501414D01*
X108132Y-502044D01*
X108445Y-502779D01*
X108523Y-503829D01*
X108445Y-504879D01*
X108132Y-505614D01*
X107740Y-506244D01*
X107270Y-506664D01*
X106643Y-506979D01*
X105077D01*
G01X117833D02*
Y-500679D01*
X119792D01*
X120418Y-500994D01*
X120810Y-501414D01*
X120967Y-502254D01*
X120810Y-503094D01*
X120340Y-503619D01*
X119792Y-503934D01*
X117833D01*
G01X119792D02*
X120967Y-506979D01*
G01X123977D02*
Y-500679D01*
X125543D01*
X126170Y-500994D01*
X126640Y-501414D01*
X127032Y-502044D01*
X127345Y-502779D01*
X127423Y-503829D01*
X127345Y-504879D01*
X127032Y-505614D01*
X126640Y-506244D01*
X126170Y-506664D01*
X125543Y-506979D01*
X123977D01*
G01X132000Y-507189D02*
X131843Y-507084D01*
Y-506874D01*
X132000Y-506769D01*
X132157Y-506874D01*
Y-507084D01*
X132000Y-507189D01*
G01X28300Y-494279D02*
X25780Y-493862D01*
X23575Y-492196D01*
X21685Y-489696D01*
X20425Y-486779D01*
X19795Y-483446D01*
Y-480112D01*
X20425Y-476779D01*
X21685Y-473862D01*
X23575Y-471363D01*
X25780Y-469696D01*
X28300Y-469279D01*
X30820Y-469696D01*
X33025Y-471363D01*
X34915Y-473862D01*
X36175Y-476779D01*
X36805Y-480112D01*
Y-483446D01*
X36175Y-486779D01*
X34915Y-489696D01*
X33025Y-492196D01*
X30820Y-493862D01*
X28300Y-494279D01*
G01X30820Y-487612D02*
X34600Y-494279D01*
G01X48145Y-477613D02*
Y-489279D01*
X49405Y-492196D01*
X51295Y-493862D01*
X53500Y-494279D01*
X55705Y-493862D01*
X57595Y-492196D01*
X58855Y-489279D01*
G01Y-494279D02*
Y-477613D01*
G01X84370Y-494279D02*
Y-477613D01*
G01Y-480529D02*
X83110Y-478863D01*
X81220Y-478029D01*
X79015Y-477613D01*
X76810Y-478446D01*
X74920Y-480112D01*
X73660Y-482613D01*
X73030Y-485946D01*
X73660Y-489279D01*
X74920Y-491780D01*
X76810Y-493446D01*
X79015Y-494279D01*
X81220Y-493862D01*
X83110Y-492613D01*
X84370Y-490946D01*
G01X98545Y-494279D02*
Y-477613D01*
G01Y-481779D02*
X99805Y-479696D01*
X101695Y-478029D01*
X104215Y-477613D01*
X106420Y-478029D01*
X108310Y-479696D01*
X109255Y-482613D01*
Y-494279D01*
G01X129100Y-469279D02*
Y-494279D01*
G01X124690Y-477613D02*
X133510D01*
G01X159970Y-494279D02*
Y-477613D01*
G01Y-480529D02*
X158710Y-478863D01*
X156820Y-478029D01*
X154615Y-477613D01*
X152410Y-478446D01*
X150520Y-480112D01*
X149260Y-482613D01*
X148630Y-485946D01*
X149260Y-489279D01*
X150520Y-491780D01*
X152410Y-493446D01*
X154615Y-494279D01*
X156820Y-493862D01*
X158710Y-492613D01*
X159970Y-490946D01*
G01X204679Y-508436D02*
Y-500436D01*
X207079D01*
X207879Y-500836D01*
X208479Y-501769D01*
X208679Y-502836D01*
X208479Y-503903D01*
X207979Y-504703D01*
X207079Y-505103D01*
X204679D01*
G01X212179Y-508436D02*
X214679Y-500436D01*
X217179Y-508436D01*
G01X216279Y-505636D02*
X213079D01*
G01X220579Y-507370D02*
X221379Y-508036D01*
X222279Y-508436D01*
X223079D01*
X223879Y-508036D01*
X224479Y-507370D01*
X224779Y-506436D01*
X224579Y-505503D01*
X224079Y-504703D01*
X223179Y-504169D01*
X221979Y-503903D01*
X221279Y-503369D01*
X220979Y-502436D01*
X221179Y-501503D01*
X221679Y-500836D01*
X222379Y-500436D01*
X223079D01*
X223779Y-500703D01*
X224379Y-501369D01*
G01X230679Y-500436D02*
Y-508436D01*
G01X228379Y-500436D02*
X232979D01*
G01X237379Y-505769D02*
X239979D01*
G01X247479Y-504169D02*
X247879Y-503769D01*
X248179Y-503103D01*
X248379Y-502169D01*
X248179Y-501369D01*
X247779Y-500836D01*
X247079Y-500436D01*
X244379D01*
Y-508436D01*
X247679D01*
X248379Y-507903D01*
X248779Y-507103D01*
X248979Y-506169D01*
X248779Y-505236D01*
X248179Y-504436D01*
X247479Y-504169D01*
X244379D01*
G01X254679Y-508436D02*
X253879Y-508303D01*
X253179Y-507769D01*
X252579Y-506969D01*
X252179Y-506036D01*
X251979Y-504969D01*
Y-503903D01*
X252179Y-502836D01*
X252579Y-501903D01*
X253179Y-501103D01*
X253879Y-500569D01*
X254679Y-500436D01*
X255479Y-500569D01*
X256179Y-501103D01*
X256779Y-501903D01*
X257179Y-502836D01*
X257379Y-503903D01*
Y-504969D01*
X257179Y-506036D01*
X256779Y-506969D01*
X256179Y-507769D01*
X255479Y-508303D01*
X254679Y-508436D01*
G01X262679Y-500436D02*
Y-508436D01*
G01X260379Y-500436D02*
X264979D01*
G01X199650Y-473979D02*
Y-481979D01*
X203650D01*
G01X211450D02*
Y-476646D01*
G01Y-477579D02*
X211050Y-477046D01*
X210450Y-476779D01*
X209750Y-476646D01*
X209050Y-476912D01*
X208450Y-477446D01*
X208050Y-478246D01*
X207850Y-479312D01*
X208050Y-480379D01*
X208450Y-481179D01*
X209050Y-481712D01*
X209750Y-481979D01*
X210450Y-481846D01*
X211050Y-481446D01*
X211450Y-480913D01*
G01X215550Y-484379D02*
X216150Y-484646D01*
X216950Y-484379D01*
X217450Y-483846D01*
X217850Y-483179D01*
X218450Y-481046D01*
X219750Y-476646D01*
G01X216550D02*
X218450Y-481046D01*
G01X224150Y-478379D02*
X227350D01*
X227050Y-477446D01*
X226550Y-476912D01*
X225850Y-476646D01*
X225150Y-476779D01*
X224550Y-477179D01*
X224150Y-478112D01*
X223950Y-478913D01*
Y-479712D01*
X224150Y-480512D01*
X224650Y-481312D01*
X225250Y-481846D01*
X225950Y-481979D01*
X226650Y-481712D01*
X227350Y-480913D01*
G01X232250Y-481979D02*
Y-476646D01*
G01Y-477712D02*
X232750Y-477179D01*
X233250Y-476779D01*
X233950Y-476646D01*
X234450Y-476779D01*
X235050Y-477179D01*
G01X223350Y-531979D02*
Y-523979D01*
X227950Y-531979D01*
Y-523979D01*
G01X233650Y-526646D02*
Y-531979D01*
G01Y-524512D02*
X233450Y-524379D01*
Y-524112D01*
X233650Y-523979D01*
X233850Y-524112D01*
Y-524379D01*
X233650Y-524512D01*
G01X239950Y-531979D02*
Y-526646D01*
G01Y-527979D02*
X240350Y-527312D01*
X240950Y-526779D01*
X241750Y-526646D01*
X242450Y-526779D01*
X243050Y-527312D01*
X243350Y-528246D01*
Y-531979D01*
G01X251450D02*
Y-526646D01*
G01Y-527579D02*
X251050Y-527046D01*
X250450Y-526779D01*
X249750Y-526646D01*
X249050Y-526912D01*
X248450Y-527446D01*
X248050Y-528246D01*
X247850Y-529312D01*
X248050Y-530379D01*
X248450Y-531179D01*
X249050Y-531712D01*
X249750Y-531979D01*
X250450Y-531846D01*
X251050Y-531446D01*
X251450Y-530913D01*
G01X326250Y-525312D02*
X326850Y-524512D01*
X327550Y-524112D01*
X328350Y-523979D01*
X329350Y-524246D01*
X330050Y-524912D01*
X330250Y-525712D01*
X330150Y-526513D01*
X329750Y-527179D01*
X327750Y-528512D01*
X326850Y-529446D01*
X326250Y-530779D01*
X326050Y-531979D01*
X330250D01*
G01X336150Y-523979D02*
X335350Y-524246D01*
X334750Y-524912D01*
X334350Y-525712D01*
X334050Y-526779D01*
X333950Y-527979D01*
X334050Y-529179D01*
X334350Y-530246D01*
X334750Y-531046D01*
X335350Y-531712D01*
X336150Y-531979D01*
X336950Y-531712D01*
X337550Y-531046D01*
X337950Y-530246D01*
X338250Y-529179D01*
X338350Y-527979D01*
X338250Y-526779D01*
X337950Y-525712D01*
X337550Y-524912D01*
X336950Y-524246D01*
X336150Y-523979D01*
G01X342250Y-525312D02*
X342850Y-524512D01*
X343550Y-524112D01*
X344350Y-523979D01*
X345350Y-524246D01*
X346050Y-524912D01*
X346250Y-525712D01*
X346150Y-526513D01*
X345750Y-527179D01*
X343750Y-528512D01*
X342850Y-529446D01*
X342250Y-530779D01*
X342050Y-531979D01*
X346250D01*
G01X349950Y-530379D02*
X350550Y-531312D01*
X351350Y-531846D01*
X352250Y-531979D01*
X353050Y-531846D01*
X353850Y-531179D01*
X354350Y-530379D01*
X354450Y-529579D01*
X354250Y-528646D01*
X353550Y-527979D01*
X352850Y-527712D01*
X351950D01*
G01X352850D02*
X353450Y-527312D01*
X353950Y-526646D01*
X354150Y-525846D01*
X353950Y-525046D01*
X353450Y-524379D01*
X352550Y-523979D01*
X351650Y-524112D01*
X350750Y-524646D01*
G01X358350Y-532246D02*
X361950Y-523979D01*
G01X368150D02*
X367350Y-524246D01*
X366750Y-524912D01*
X366350Y-525712D01*
X366050Y-526779D01*
X365950Y-527979D01*
X366050Y-529179D01*
X366350Y-530246D01*
X366750Y-531046D01*
X367350Y-531712D01*
X368150Y-531979D01*
X368950Y-531712D01*
X369550Y-531046D01*
X369950Y-530246D01*
X370250Y-529179D01*
X370350Y-527979D01*
X370250Y-526779D01*
X369950Y-525712D01*
X369550Y-524912D01*
X368950Y-524246D01*
X368150Y-523979D01*
G01X373950Y-530379D02*
X374550Y-531312D01*
X375350Y-531846D01*
X376250Y-531979D01*
X377050Y-531846D01*
X377850Y-531179D01*
X378350Y-530379D01*
X378450Y-529579D01*
X378250Y-528646D01*
X377550Y-527979D01*
X376850Y-527712D01*
X375950D01*
G01X376850D02*
X377450Y-527312D01*
X377950Y-526646D01*
X378150Y-525846D01*
X377950Y-525046D01*
X377450Y-524379D01*
X376550Y-523979D01*
X375650Y-524112D01*
X374750Y-524646D01*
G01X382350Y-532246D02*
X385950Y-523979D01*
G01X390250Y-525312D02*
X390850Y-524512D01*
X391550Y-524112D01*
X392350Y-523979D01*
X393350Y-524246D01*
X394050Y-524912D01*
X394250Y-525712D01*
X394150Y-526513D01*
X393750Y-527179D01*
X391750Y-528512D01*
X390850Y-529446D01*
X390250Y-530779D01*
X390050Y-531979D01*
X394250D01*
G01X401350D02*
Y-523979D01*
X397650Y-529712D01*
X402650D01*
G01X325950Y-506979D02*
Y-498979D01*
X327950D01*
X328750Y-499379D01*
X329350Y-499912D01*
X329850Y-500712D01*
X330250Y-501646D01*
X330350Y-502979D01*
X330250Y-504312D01*
X329850Y-505246D01*
X329350Y-506046D01*
X328750Y-506579D01*
X327950Y-506979D01*
X325950D01*
G01X333650D02*
X336150Y-498979D01*
X338650Y-506979D01*
G01X337750Y-504179D02*
X334550D01*
G01X344150Y-498979D02*
X343350Y-499246D01*
X342750Y-499912D01*
X342350Y-500712D01*
X342050Y-501779D01*
X341950Y-502979D01*
X342050Y-504179D01*
X342350Y-505246D01*
X342750Y-506046D01*
X343350Y-506712D01*
X344150Y-506979D01*
X344950Y-506712D01*
X345550Y-506046D01*
X345950Y-505246D01*
X346250Y-504179D01*
X346350Y-502979D01*
X346250Y-501779D01*
X345950Y-500712D01*
X345550Y-499912D01*
X344950Y-499246D01*
X344150Y-498979D01*
G01X350250Y-506979D02*
Y-498979D01*
X354050D01*
G01X352650Y-502846D02*
X350250D01*
G01X360150Y-498979D02*
X359350Y-499246D01*
X358750Y-499912D01*
X358350Y-500712D01*
X358050Y-501779D01*
X357950Y-502979D01*
X358050Y-504179D01*
X358350Y-505246D01*
X358750Y-506046D01*
X359350Y-506712D01*
X360150Y-506979D01*
X360950Y-506712D01*
X361550Y-506046D01*
X361950Y-505246D01*
X362250Y-504179D01*
X362350Y-502979D01*
X362250Y-501779D01*
X361950Y-500712D01*
X361550Y-499912D01*
X360950Y-499246D01*
X360150Y-498979D01*
G01X368150D02*
Y-506979D01*
G01X365850Y-498979D02*
X370450D01*
G01X373550Y-506979D02*
Y-498979D01*
X376150Y-505646D01*
X378750Y-498979D01*
Y-506979D01*
G01X384950Y-502712D02*
X385350Y-502312D01*
X385650Y-501646D01*
X385850Y-500712D01*
X385650Y-499912D01*
X385250Y-499379D01*
X384550Y-498979D01*
X381850D01*
Y-506979D01*
X385150D01*
X385850Y-506446D01*
X386250Y-505646D01*
X386450Y-504712D01*
X386250Y-503779D01*
X385650Y-502979D01*
X384950Y-502712D01*
X381850D01*
G01X390950Y-498979D02*
X393350D01*
G01X392150D02*
Y-506979D01*
G01X390950D02*
X393350D01*
G01X398150Y-505379D02*
X398650Y-506179D01*
X399250Y-506712D01*
X399950Y-506979D01*
X400750Y-506712D01*
X401350Y-506179D01*
X401950Y-505379D01*
X402150Y-504312D01*
Y-498979D01*
G01X408150D02*
X407350Y-499246D01*
X406750Y-499912D01*
X406350Y-500712D01*
X406050Y-501779D01*
X405950Y-502979D01*
X406050Y-504179D01*
X406350Y-505246D01*
X406750Y-506046D01*
X407350Y-506712D01*
X408150Y-506979D01*
X408950Y-506712D01*
X409550Y-506046D01*
X409950Y-505246D01*
X410250Y-504179D01*
X410350Y-502979D01*
X410250Y-501779D01*
X409950Y-500712D01*
X409550Y-499912D01*
X408950Y-499246D01*
X408150Y-498979D01*
G01X343750Y-481979D02*
Y-473979D01*
X347550D01*
G01X346150Y-477846D02*
X343750D01*
G01X353650Y-473979D02*
X352850Y-474246D01*
X352250Y-474912D01*
X351850Y-475712D01*
X351550Y-476779D01*
X351450Y-477979D01*
X351550Y-479179D01*
X351850Y-480246D01*
X352250Y-481046D01*
X352850Y-481712D01*
X353650Y-481979D01*
X354450Y-481712D01*
X355050Y-481046D01*
X355450Y-480246D01*
X355750Y-479179D01*
X355850Y-477979D01*
X355750Y-476779D01*
X355450Y-475712D01*
X355050Y-474912D01*
X354450Y-474246D01*
X353650Y-473979D01*
G01X361650D02*
Y-481979D01*
G01X359350Y-473979D02*
X363950D01*
G01X366650Y-484646D02*
X372650D01*
G01X375050Y-481979D02*
Y-473979D01*
X377650Y-480646D01*
X380250Y-473979D01*
Y-481979D01*
G01X386450Y-477712D02*
X386850Y-477312D01*
X387150Y-476646D01*
X387350Y-475712D01*
X387150Y-474912D01*
X386750Y-474379D01*
X386050Y-473979D01*
X383350D01*
Y-481979D01*
X386650D01*
X387350Y-481446D01*
X387750Y-480646D01*
X387950Y-479712D01*
X387750Y-478779D01*
X387150Y-477979D01*
X386450Y-477712D01*
X383350D01*
G01X390650Y-484646D02*
X396650D01*
G01X403650Y-481979D02*
X399650D01*
Y-473979D01*
X403650D01*
G01X402050Y-477846D02*
X399650D01*
G01X407050Y-481979D02*
Y-473979D01*
X409650Y-480646D01*
X412250Y-473979D01*
Y-481979D01*
G01X417650D02*
X418350Y-481846D01*
X419150Y-481446D01*
X419650Y-480779D01*
X419850Y-479846D01*
X419650Y-478913D01*
X419050Y-478112D01*
X418150Y-477712D01*
X417150D01*
X416550Y-477446D01*
X416050Y-476779D01*
X415850Y-475846D01*
X416150Y-474912D01*
X416850Y-474246D01*
X417650Y-473979D01*
X418450Y-474246D01*
X419150Y-474912D01*
X419450Y-475846D01*
X419250Y-476779D01*
X418750Y-477446D01*
X418150Y-477712D01*
X417150D01*
X416250Y-478112D01*
X415650Y-478913D01*
X415450Y-479846D01*
X415650Y-480779D01*
X416150Y-481446D01*
X416950Y-481846D01*
X417650Y-481979D01*
G01X423950Y-481046D02*
X424650Y-481712D01*
X425450Y-481979D01*
X426250Y-481712D01*
X426950Y-480913D01*
X427450Y-479712D01*
X427650Y-478512D01*
Y-477046D01*
X427450Y-475846D01*
X426950Y-474779D01*
X426350Y-474246D01*
X425650Y-473979D01*
X424850Y-474246D01*
X424250Y-474779D01*
X423850Y-475579D01*
X423650Y-476646D01*
X423850Y-477579D01*
X424350Y-478512D01*
X424950Y-479046D01*
X425650Y-479179D01*
X426450Y-478913D01*
X427050Y-478246D01*
X427650Y-477046D01*
G01X433650Y-473979D02*
X432850Y-474246D01*
X432250Y-474912D01*
X431850Y-475712D01*
X431550Y-476779D01*
X431450Y-477979D01*
X431550Y-479179D01*
X431850Y-480246D01*
X432250Y-481046D01*
X432850Y-481712D01*
X433650Y-481979D01*
X434450Y-481712D01*
X435050Y-481046D01*
X435450Y-480246D01*
X435750Y-479179D01*
X435850Y-477979D01*
X435750Y-476779D01*
X435450Y-475712D01*
X435050Y-474912D01*
X434450Y-474246D01*
X433650Y-473979D01*
G01X439450Y-481979D02*
Y-473979D01*
G01X443250D02*
X439450Y-478913D01*
G01X443850Y-481979D02*
X441150Y-476646D01*
G01X414650Y-534979D02*
Y-526979D01*
X413450Y-528579D01*
G01Y-534979D02*
X415850D01*
G01X420750Y-531646D02*
X421450Y-530712D01*
X422050Y-530179D01*
X422850Y-529912D01*
X423550Y-530179D01*
X424050Y-530712D01*
X424450Y-531512D01*
X424550Y-532446D01*
X424450Y-533246D01*
X424050Y-534046D01*
X423450Y-534712D01*
X422750Y-534979D01*
X421950Y-534712D01*
X421250Y-533913D01*
X420850Y-532712D01*
X420750Y-531379D01*
X420950Y-529646D01*
X421250Y-528712D01*
X421750Y-527779D01*
X422450Y-527112D01*
X423150Y-526979D01*
X423850Y-527246D01*
X424350Y-527912D01*
G01X430650Y-535246D02*
X430450Y-535112D01*
Y-534846D01*
X430650Y-534712D01*
X430850Y-534846D01*
Y-535112D01*
X430650Y-535246D01*
G01X436750Y-531646D02*
X437450Y-530712D01*
X438050Y-530179D01*
X438850Y-529912D01*
X439550Y-530179D01*
X440050Y-530712D01*
X440450Y-531512D01*
X440550Y-532446D01*
X440450Y-533246D01*
X440050Y-534046D01*
X439450Y-534712D01*
X438750Y-534979D01*
X437950Y-534712D01*
X437250Y-533913D01*
X436850Y-532712D01*
X436750Y-531379D01*
X436950Y-529646D01*
X437250Y-528712D01*
X437750Y-527779D01*
X438450Y-527112D01*
X439150Y-526979D01*
X439850Y-527246D01*
X440350Y-527912D01*
G01X459650Y-534979D02*
Y-526979D01*
X458450Y-528579D01*
G01Y-534979D02*
X460850D01*
G01X467450D02*
X467650Y-533246D01*
X467950Y-531779D01*
X468350Y-530446D01*
X468850Y-528979D01*
X469650Y-526979D01*
X465650D01*
G01X475650Y-535246D02*
X475450Y-535112D01*
Y-534846D01*
X475650Y-534712D01*
X475850Y-534846D01*
Y-535112D01*
X475650Y-535246D01*
G01X481750Y-528312D02*
X482350Y-527512D01*
X483050Y-527112D01*
X483850Y-526979D01*
X484850Y-527246D01*
X485550Y-527912D01*
X485750Y-528712D01*
X485650Y-529513D01*
X485250Y-530179D01*
X483250Y-531512D01*
X482350Y-532446D01*
X481750Y-533779D01*
X481550Y-534979D01*
X485750D01*
G01X479650Y-508379D02*
X480150Y-509179D01*
X480750Y-509712D01*
X481450Y-509979D01*
X482250Y-509712D01*
X482850Y-509179D01*
X483450Y-508379D01*
X483650Y-507312D01*
Y-501979D01*
M02*
